TITLE: Bill of Materials
DATE: 05/18/2017
DESIGN: baseboard_fab2
TEMPLATE: D:\Cadence\SPB_16.6\share\cdssetup\template.bom
CALLOUT: 

Part Name	Ref Des	Qty	PART_NUMBER	MATERIAL	POP	CONFIG	BOM_DS	BOM_SS	GROUP	FAIR_SS
120R2F-GP_RCL_GP-120R2F-GP,64.12005.6DL,120OHM,1%,1/16W,0402	R25W1,R25W2,R25W5,R25W6,R25W7,R25W8,R25W9,R25W10,R25W11,R25W12,R25W13,R25W14,R25W15,R25W16,R25W17,R25W18,R25W19,R25W20,R25W21,R25W22,R25W23,R25W24,R25W25,R25W26,R25W27,R25W28,R25W31,R25W32,R25W33,R25W34,R25W35,R25W36,R25W37,R25W38,R25W39,R25W40,R25W41,R25W42,R25W43,R25W44,R25W45,R25W46,R25W47,R25W48,R25W49,R25W50,R25W51,R25W52	48	64.12005.6DL	?	?	?	?	?	?	?
120R2F-GP_RCL_GP-120R2F-GP,64.12005.6DL,120OHM,1%,1/16W,0402	R25W3,R25W4,R25W29	3	64.12005.6DL	?	NOPOP	?	?	?	?	?
18KR2F-GP_RCL_GP-18KR2F-GP,64.18025.6DL,18KOHM,1%,1/16W,0402	R25W58	1	64.18025.6DL	?	?	?	?	?	?	?
1K82R2F-1-GP_SMD-RG-1K82R2F-1-GP,64.18215.6DL,1.82KOHM,1%,1/16W,0402	R1U28,R1U44	2	64.18215.6DL	?	?	?	?	?	?	?
1MR2F-L-GP_SMD-RG1-1MR2F-L-GP,64.10045.L1L,1MOHM,1%,1/16W,0402	R1W1,R1W3,R1W6	3	64.10045.L1L	?	?	?	?	?	?	?
1R3F-GP_RCL_GP-1R3F-GP,64.1R005.55L,1 OHM,1%,1/10W,0603	RT2,RT4,RT6,RT10,RT12,RT13,RT16,RT18,RT20,RT24,RT26,RT27,RT29,RT34,RT38,RT39,RT42,RT43,RT45,RT48	20	64.1R005.55L	?	NOPOP	?	?	?	?	?
1R3F-GP_RCL_GP-1R3F-GP,64.1R005.55L,1 OHM,1%,1/10W,0603	RT7,RT22,RT32,RT35	4	64.1R005.55L	?	NOPOP	?	?	NOPOP	?	?
200R2F-L1-GP_SMD-RG4-200R2F-L1-GP,64.20005.L0L,200 OHM,1%,1/16W,0402	R25W67	1	64.20005.L0L	?	?	?	?	?	AST2500	?
21K5R2F-GP_RCL_GP-21K5R2F-GP,64.21525.6DL,21.5KOHM,1%,1/16W,0402	R9W31	1	64.21525.6DL	?	?	?	?	?	?	?
232KR2F-2-GP_SMD-RG1-232KR2F-2-GP,64.23235.L0L,232KOHM,1%,1/16W,0402	R6W3	1	64.23235.L0L	?	?	?	?	?	?	?
270KR2F-GP_RCL_GP-270KR2F-GP,64.27035.6DL,270KOHM,1%,1/16W,0402	R9P13	1	64.27035.6DL	?	?	?	?	?	?	?
2K15R2F-1-GP_SMD-RG1-2K15R2F-1-GP,64.21515.6DL,2.15K OHM,1%,1/16W,0402	R8E30,R8E36	2	64.21515.6DL	?	?	?	?	?	?	?
2SB2907A-B0-00001-GP_DISCRET-GB1-2SB2907A-B0-00001-GP,006.02907.001A	Q1E1,Q9B1	2	006.02907.001A	?	?	?	?	?	?	?
374R2F-1-GP_SMD-RG-374R2F-1-GP,64.37405.6DL,374 OHM,1%,1/16W,0402	R1U43,R2T36,R3P45,R7D33,R25W183	5	64.37405.6DL	?	?	?	?	?	?	?
47KR2F-GP_RCL_GP-47KR2F-GP,64.47025.6DL,47KOHM,1%,1/16W,0402	R3W4	1	64.47025.6DL	?	?	?	?	?	?	?
4D02R2F-GP_SMD-RG2-4D02R2F-GP,64.4R025.6DL,4.02OHM,1%,1/16W,0402	R12W3,R12W8,R12W13,R12W18	4	64.4R025.6DL	?	?	?	?	?	?	?
4K42R2F-GP_SMD-RG-4K42R2F-GP,64.44215.6DL,4.42KOHM,1%,1/16W,0402	R9F6	1	64.44215.6DL	?	?	?	?	?	?	?
5K1R2F-2-GP_SMD-RG-5K1R2F-2-GP,64.51015.6DL,5.1KOHM,1%,1/16W,0402	R9F31	1	64.51015.6DL	?	?	?	?	?	?	?
649R2F-GP_RCL_GP-649R2F-GP,64.64905.6DL,649OHM,1%,1/16W,0402	R1U33	1	64.64905.6DL	?	?	?	?	?	?	?
665KR2B-GP_SMD-RG2-665KR2B-GP,064.6653D.06DD,665KOHM,0.1%,1/16W,0402	R12W5,R12W10,R12W15,R12W20	4	064.6653D.06DD	?	NOPOP	?	?	?	?	?
665KR5B-1-GP_SMD-RG3-665KR5B-1-GP,064.6653F.M001,665K OHM,0.1%,1/8W,AT0805	R12W1,R12W2,R12W6,R12W7,R12W11,R12W12,R12W16,R12W17	8	064.6653F.M001	?	?	064.1003F.M001	?	?	?	?
74CBTLV1G125_SMLF-IC,C88177-001	U1M4,U7D1,U8W1	3	C88177-001	IC	?	?	?	?	?	?
74CBTLV1G125_SMLF-IC,C88177-001	U1M5,U4R1,U6M1,U9A5	4	C88177-001	IC	NOPOP	?	?	?	?	?
74CBTLV1G125_SMLF-IC,C88177-001	U1M6	1	C88177-001	IC	?	?	?	?	MCP	?
82KR2F-1-GP_SMD-RG-82KR2F-1-GP,64.82025.6DL,82KOHM,1%,1/16W,0402	RN8F6	1	64.82025.6DL	?	?	?	?	?	?	?
887R2F-L-GP_SMD-RG-887R2F-L-GP,64.88705.6DL,887OHM,1%,1/16W,0402	R2R8,R9B7	2	64.88705.6DL	?	?	?	?	?	?	?
ADM1085_SMT-IC,H46130-001	U7D3	1	H46130-001	IC	?	?	?	?	?	?
ADM1278_SM-IC,G99251-001	EU1D2	1	G99251-001	IC	?	?	?	?	?	?
ADM809_SMLF-IC,D23047-001	U1L3,U8E2	2	D23047-001	IC	?	?	?	?	?	?
AST2520A1-GP-GP_ASIC2-GB1-AST2520A1-GP-GP,071.2520A.M001	U25W4	1	071.2520A.M001	?	?	?	?	?	?	?
AT24C64_SOICLF-IC,C47049-001	U6W3,U8D4	2	C47049-001	IC	?	?	?	?	?	?
BATTERY_PLCLF-202168-001	BT8G1	1	202168-001	?	?	?	?	?	?	?
BLM15AG121SN-1GP_DISCRET-G-BLM15AG121SN-1GP,68.00084.921	FB25W1,FB25W2,FB25W3,FB25W4,FB25W5	5	68.00084.921	?	?	?	?	?	?	?
BLM31SN500SN1L-GP_DISCRET-GB1-BLM31SN500SN1L-GP,068.00007.0011,50OHM@100MHZ,1MA,DCR=1.6MOHM	FB9E1	1	068.00007.0011	?	?	?	?	?	?	?
BSL308C-H6327-GP_DISCRET-GB1-BSL308C-H6327-GP,075.00308.007C	Q12W1,Q12W2,Q12W3,Q12W4	4	075.00308.007C	?	?	?	?	?	?	?
CAPP_2626-270UF,16V,20%,OSCON,A31228-047	C1B10,C1C1,C1C2,C1E18,C4C12,C4D2,C4E16,C7G2	8	A31228-047	OSCON	?	?	?	?	?	?
CAPP_3018-470UF,2.5V,20%,ALUM,699013-049	C3L6,C3L14,C3N26,C3N35,C3N38,C3U1,C3U5,C3U8,C4E7,C4L5,C6A5,C6N1,C6N4,C6N9,C6P8,C6P14,C6P18,C6P23,C6R3,C6R5,C6R9,C6R12,C7G28,C9L2,C9L4,C9L9,C9L12,C9N11,C9N20,C9N24,C9P5,C9P8,C9P18,C9P23,C9R3,C9R9,C9T5,C9U2,C9U5,C9U9	40	699013-049	ALUM	?	?	?	?	PWR_BULK_CAP	?
CAPP_3018-470UF,2.5V,20%,ALUM,699013-049	C3N14,C3R4,C4C1,C4E24,C4E29,C4R1,C6R16	7	699013-049	ALUM	?	?	?	?	PWR_MCP_CAP	?
CAPP_3018-68UF,16V,20%,TANT,724613-112	C1M5,C1R23,C3B6,C3T3,C3T6,C3T13,C3T15,C4B14,C4F4,C4F5,C4M6,C4M7,C6N5,C7M6,C9M3,C9T3	16	724613-112	TANT	?	?	?	?	?	?
CAPP_4040LF-470UF,16V,20%,ALUM,A93539-036	C1B14,C1F7,C4B13,C4F6	4	A93539-036	ALUM	?	?	?	?	?	?
CAPP_7343-220UF,4V,20%,POSCAP,724613-067	C4F11,C4M1,C4T3,C6L8	4	724613-067	POSCAP	?	?	?	?	PWR_BULK_CAP	?
CAPP_7343HLF-330UF,10V,20%,POSCAP,724613-043	C9B8	1	724613-043	POSCAP	?	?	?	?	?	?
CAPP_7343LF-330UF,6.3V,20%,POSCAP,724613-042	C3B3,C4F7,C6B7,C6F4	4	724613-042	POSCAP	?	?	?	?	PWR_BULK_CAP	?
CAPP_SM-470UF,2V,20%,ALUM,699013-031	C2L25,C2L46,C3L18,C3L19,C3L20,C3L21,C7A27,C8A15	8	699013-031	ALUM	?	?	?	?	?	?
CAP_0402-0.027UF,16V,10%,X7R,A36096-129	C4B6,C4G8,C7B11,C7F10	4	A36096-129	X7R	?	?	?	?	?	?
CAP_0402-0.047UF,25V,10%,X7R,A36096-090	C3P45	1	A36096-090	X7R	?	?	?	?	?	?
CAP_0402-0.220UF,16V,10%,X7R,A36096-104	C1A18,C1C12,C1C24,C1D10,C1D20,C1D36,C1E11,C1G11,C4C8,C4C17,C4D9,C4D28,C4D50,C4E17,C4E18,C7A12,C7A43,C7A44,C7C14,C7G31	20	A36096-104	X7R	?	?	?	?	?	?
CAP_0402-0.220UF,16V,10%,X7R,A36096-104	C1A8,C1F26,C7A22,C7G38	4	A36096-104	X7R	?	?	?	NOPOP	?	?
CAP_0402-0.22UF,16V,10%,X7R,A36096-155	C1A13,C1G29,C7A25,C7G41	4	A36096-155	X7R	?	?	?	NOPOP	?	?
CAP_0402-0.22UF,16V,10%,X7R,A36096-155	C1B21,C1C4,C1D6,C1D16,C1D33,C1E7,C1E25,C1F2,C1F3,C1F4,C1F5,C1F6,C1F8,C1F10,C1F11,C1F12,C1F13,C1F14,C1F15,C1F16,C1F17,C1F18,C1F20,C1G5,C1M6,C1M7,C1M8,C1M9,C1M10,C1M11,C1M12,C1M13,C1M14,C1M15,C1M16,C1M17,C1M18,C1M19,C1R1,C1R2,C1R3,C1R4,C1R5,C1R6,C1R7,C1R8,C1R9,C1R10,C1W20,C2M14,C2M15,C2R7,C2R8,C2R9,C2R10,C2R13,C2R14,C2T10,C2T11,C2T13,C2T14,C2T20,C2T23,C3M37,C3M40,C3M41,C3M44,C3M45,C3N8,C3N9,C3N13,C4C5,C4D5,C4D13,C4D47,C4E5,C4E23,C4E27,C7A8,C7A17,C7A41,C7B25,C7B26,C7B27,C7B28,C7B29,C7C1,C7C2,C7C3,C7C18,C7G5,C7G6,C7G7,C7G8,C7G9,C7G10,C7G11,C7G12,C7G13,C7G14,C7G15,C7G16,C7G17,C7G18,C7G19,C7G20,C7G21,C7G22,C7G23,C7G24,C7G25,C7G26,C7G34,C8G1,C8G2,C8G3,C8G4,C8G5,C8G6,C8G7,C8G8,C8G9,C8G10,C9N1,C9N2,C9N3,C9N4,C9N5,C9N6,C9N7,C9N8,C9N9,C9N10,C9N12,C9N14,C9N15,C9N16,C9N17,C9N18	139	A36096-155	X7R	?	?	?	?	?	?
CAP_0402-0.22UF,16V,10%,X7R,A36096-155	C2U3,C2U4,C2U5,C2U6,C2U7,C2U8,C2U9,C2U10,C2U11,C2U12,C2U13,C2U14,C2U15,C2U16,C2U17,C2U18,C3M1,C3M2,C3M3,C3M4,C3M11,C3M12,C3M13,C3M14,C3M25,C3M26,C3M28,C3M32,C3M33,C3M34,C3M35,C3M36,C3P11,C3P13,C3P15,C3P17,C3P18,C3P20,C3P23,C3P25,C3P27,C3P28,C3P30,C3P32,C3P35,C3P37,C3P39,C3P40,C6B4,C6B5,C6B6,C6B8,C6B9,C6B10,C6B11,C6B12,C6B13,C6B14,C6B15,C6B16,C6B17,C6B18,C6B19,C6B20	64	A36096-155	X7R	?	?	?	?	PCIE_UPLINK	?
CAP_0402-0.22UF,16V,10%,X7R,A36096-155	C3P10,C3P12,C3P14,C3P16,C3P19,C3P21,C3P22,C3P24,C3P26,C3P29,C3P31,C3P33,C3P34,C3P36,C3P38,C3P41,C826,C827,C828,C829,C830,C831,C832,C833,C834,C835,C840,C841,C842,C843,C844,C845	32	A36096-155	X7R	?	?	?	?	PCIE_RISER	?
CAP_0402-0.22UF,16V,10%,X7R,A36096-155	C8F7,C8F12	2	A36096-155	X7R	?	?	?	?	M2_PCIE	?
CAP_0402-1.0UF,16V,10%,X6S,D97712-011	C1A9,C1A19,C1B20,C1C5,C1C15,C1C26,C1D7,C1D12,C1D17,C1D19,C1D23,C1D25,C1D32,C1D35,C1E8,C1E13,C1E24,C1F27,C1G6,C1G13,C1L1,C1L19,C1L119,C1U19,C3M9,C3P50,C3T10,C4A8,C4A9,C4A10,C4A14,C4C6,C4C9,C4C18,C4D7,C4D10,C4D16,C4D30,C4D46,C4D48,C4E10,C4E15,C4E19,C4E22,C4E26,C4G4,C4G15,C4G16,C4G18,C4G21,C6L11,C7A6,C7A7,C7A9,C7A10,C7A11,C7A16,C7A21,C7C12,C7C17,C7D4,C7E14,C7G30,C7G33,C7G37,C8E14,C9E11,C25W1,C25W2,C25W3,C25W4,C25W5,C25W6,C25W23,C25W24,C25W25,C25W26,C25W27,C25W28,C25W32,C25W33,C25W35,C25W37,C25W40,C25W41,C25W42,C25W43,C25W44,C25W48,C25W51,C25W52,C25W53,C25W54,C25W56,C25W60,C25W66,C25W67,C25W71,C25W92,C25W94,C25W98	101	D97712-011	X6S	?	?	?	?	?	?
CAP_0402-1.0UF,16V,10%,X6S,D97712-011	C1A6,C1G28,C7A24,C7G40	4	D97712-011	X6S	?	?	?	NOPOP	?	?
CAP_0402-1.0UF,16V,10%,X6S,D97712-011	C32W5	1	D97712-011	X6S	NOPOP	?	?	?	?	?
CAP_0402-1.0UF,16V,10%,X7S,G71842-007	C9G5	1	G71842-007	X7S	?	?	?	?	NI_I210&RJ45	?
CAP_0402-1.0UF,6.3V,10%,EMPTY,D97712-004	C3W1	1	D97712-004	EMPTY	?	?	?	?	?	?
CAP_0402LF-0.022UF,16V,10%,X7R,A36096-073	C8E15	1	A36096-073	X7R	?	?	?	?	?	?
CAP_0402LF-0.039UF,25V,10%,X7R,A36096-063	C9E7	1	A36096-063	X7R	?	?	?	?	NI_I210&RJ45	?
CAP_0402LF-10.0PF,50V,5%,COG,A36094-025	C25W81,C25W82	2	A36094-025	COG	?	?	?	?	AST2500	?
CAP_0402LF-10.0PF,50V,5%,COG,A36094-025	C9G22	1	A36094-025	COG	?	?	?	?	?	?
CAP_0402LF-100.0PF,50V,5%,COG,A36095-026	C4B4,C4G6,C7B10,C7F9,C25W16,C25W57	6	A36095-026	COG	?	?	?	?	?	?
CAP_0402LF-100.0PF,50V,5%,COG,A36095-026	C25W78,C25W79	2	A36095-026	COG	?	?	?	?	AST2500	?
CAP_0402LF-1000PF,50V,10%,EMPTY,A36096-046	C4A2,C4A6,C4B5,C4G7,C4G12,C4G23,C7B9,C7F8,C8A10,C8E13,C8E17,C9F6,C9F9,C9W6	14	A36096-046	EMPTY	?	?	?	?	?	?
CAP_0402LF-1000PF,50V,10%,X7R,A36096-046	C1B4,C1C23,C1G21,C1W16,C3P6,C4A3,C4A12,C4B8,C4D33,C4D42,C4G9,C4G13,C4G14,C7B3,C7B12,C7E10,C7F11,C7F14,C8A9,C8A11,C8F2,C9F8,C9F10,C9W10	24	A36096-046	X7R	?	?	?	?	?	?
CAP_0402LF-1000PF,50V,10%,X7R,A36096-046	CT10,CT11,CT32,CT33,CT47,CT48,CT53,CT54	8	A36096-046	X7R	NOPOP	?	?	NOPOP	?	?
CAP_0402LF-1000PF,50V,10%,X7R,A36096-046	CT2,CT3,CT4,CT5,CT8,CT9,CT14,CT15,CT18,CT19,CT20,CT22,CT23,CT26,CT27,CT28,CT29,CT34,CT35,CT37,CT38,CT41,CT42,CT43,CT44,CT49,CT50,CT55,CT56,CT58,CT59,CT61,CT62,CT64,CT65,CT68,CT69,CT71,CT72,CTI7	40	A36096-046	X7R	NOPOP	?	?	?	?	?
CAP_0402LF-12.0PF,50V,5%,COG,A36095-043	C25W72,C25W73,C25W74,C25W75,C25W76,C25W77	6	A36095-043	COG	?	?	?	?	AST2500	?
CAP_0402LF-15.0PF,50V,5%,COG,A36095-047	C7C13,C7C15,C8F18,C8F19	4	A36095-047	COG	?	?	?	?	?	?
CAP_0402LF-15.0PF,50V,5%,COG,A36095-047	C7C4,C7C5	2	A36095-047	COG	?	78.6R864.1FL	?	?	?	?
CAP_0402LF-15.0PF,50V,5%,COG,A36095-047	C9E8,C9E9	2	A36095-047	COG	?	?	?	?	NI_I210&RJ45	?
CAP_0402LF-2200PF,50V,10%,X7R,A36096-075	C4B7,C4B9,C4G10,C4G11,C7B13,C7B14,C7F12,C7F13,C8F1	9	A36096-075	X7R	?	?	?	?	?	?
CAP_0402LF-220PF,50V,10%,X7R,A36096-050	C1B11,C1B12,C1C10,C1C11,C1C16,C1D1,C1G16,C1G24,C2L2,C3N39,C4D17,C4D18,C4D29,C4D44,C4D45,C4W1,C4W2,C4W3,C4W4,C7A28,C7A29,C7G3,C7G4,C8A2	24	A36096-050	X7R	?	?	?	?	?	?
CAP_0402LF-270PF,50V,10%,X7R,A36096-065	C8E16	1	A36096-065	X7R	?	?	?	?	?	?
CAP_0402LF-33.0PF,50V,5%,COG,A36095-031	C8C1,C8C2	2	A36095-031	COG	?	?	?	?	?	?
CAP_0402LF-3300PF,50V,10%,EMPTY,A36096-091	C4A16,C4F12,C7A34,C7F3,C8F3	5	A36096-091	EMPTY	?	?	?	?	?	?
CAP_0402LF-47.0PF,50V,5%,COG,A36095-025	C1U21,C9G14,C9G15,C9G17,C9G18,C9G20,C9G21,C12W1,C12W2,C12W3,C12W4	11	A36095-025	COG	?	?	?	?	?	?
CAP_0402LF-47.0PF,50V,5%,EMPTY,A36095-025	C1E19,C1M4	2	A36095-025	EMPTY	?	?	?	?	?	?
CAP_0402LF-4700PF,50V,10%,EMPTY,A36096-066	C9G9,C9G12,C9G13,C9G16	4	A36096-066	EMPTY	?	?	?	?	NI_I210&RJ45	?
CAP_0402LF-470PF,50V,10%,EMPTY,A36096-049	C2R6,C8D3	2	A36096-049	EMPTY	?	?	?	?	?	?
CAP_0402LF-470PF,50V,10%,X7R,A36096-049	C9F22,C9G1,C9G2,C9G3	4	A36096-049	X7R	?	?	?	?	NI_I210&RJ45	?
CAP_0603-10UF,6.3V,20%,X6S,E15431-002	C1R13,C1R16,C1R17,C1R22,C1R30,C1T4	6	E15431-002	X6S	?	?	?	?	NI_I210&RJ45	?
CAP_0603-10UF,6.3V,20%,X6S,E15431-002	C1T7,C1T15,C1W7,C1W15,C2N14,C2N17,C2N21,C2N22,C2N23,C2N24,C7D2,C8A6,C8C3,C8C4,C8C5,C8C6,C9E10,C9F3	18	E15431-002	X6S	?	?	?	?	?	?
CAP_0603-10UF,6.3V,20%,X6S,E15431-002	C9W14,C9W17	2	E15431-002	X6S	NOPOP	?	?	?	?	?
CAP_0603-4.7UF,6.3V,10%,X6S,E15431-003	C4A7,C4A11,C6U11,C6U12,C25W19,C25W30,C25W36,C25W39,C25W47,C25W50,C25W62,C25W69,C25W70	13	E15431-003	X6S	?	?	?	?	?	?
CAP_0603-4.7UF,6.3V,10%,X6S,E15431-003	C25W59	1	E15431-003	X6S	NOPOP	?	?	?	?	?
CAP_0603-4.7UF,6.3V,10%,X6S,E15431-003	C3M10,C3T11,C6L12,C6U6	4	E15431-003	X6S	?	078.47521.08BD	?	?	?	?
CAP_0603LF-0.033UF,50V,10%,X7R,603269-064	C1W21,C9P14	2	603269-064	X7R	?	?	?	?	?	?
CAP_0603LF-0.1UF,25V,10%,X7R,602433-020	C4B15,C4G26,C7B30,C7F4,C8A4,C8E6,C8E12	7	602433-020	X7R	?	?	?	?	?	?
CAP_0603LF-10UF,4V,20%,X6S,E15431-001	C2M5,C2M10,C2N6,C3M17,C3M18,C3M23,C3M24,C4A15,C6L3,C6L4,C6L5,C6U13,C6U14,C6U15,C6U16,C25W29	16	E15431-001	X6S	?	?	?	?	?	?
CAP_0603LF-10UF,4V,20%,X6S,E15431-001	C2D8,C2D9,C2D10,C2D11,C3A3,C3A4,C3A7,C3A8,C3B1,C3B2,C3F3,C3F4,C3G3,C3G4,C3G7,C3G8,C4L1,C4L2,C4L3,C4L4,C4M3,C4M4,C4T5,C4T6,C4U1,C4U2,C4U3,C4U4,C5D10,C5D11,C5D12,C5D13,C6A2,C6A3,C6A6,C6A7,C6B1,C6B2,C6F5,C6F6,C6G1,C6G2,C6G4,C6G5,C7L2,C7L3,C7L6,C7L7,C7M3,C7M4,C7T2,C7T3,C7U3,C7U4,C7U5,C7U6	56	E15431-001	X6S	?	?	?	?	PWR_MLCC_CAP	?
CAP_0603LF-10UF,4V,20%,X6S,E15431-001	C3D3,C6D1	2	E15431-001	X6S	?	?	?	?	PWR_MCP_CAP	?
CAP_0805-100UF,4V,20%,X5R,602433-112	C2A8,C2A16,C2G7,C2G16,C4T4,C5A10,C5A20,C5G9,C5G20,C5L1,C5L2,C5L3,C5L14,C5M8,C5M12,C5P1,C5P2,C5P3,C5P4,C5P5,C5P6,C5P38,C5P39,C5P41,C5P42,C5P43,C5P44,C5U1,C5U10,C5U13,C5U14,C5U15,C7L1,C7P1,C7P2,C7P20,C7T1,C7U7,C8L1,C8L2,C8L11,C8M7,C8M11,C8P1,C8P2,C8P3,C8P4,C8P30,C8P31,C8P32,C8P33,C8P34,C8U1,C8U8,C8U11,C8U12	56	602433-112	X5R	?	?	?	NOPOP	PWR_MLCC_CAP	?
CAP_0805-100UF,4V,20%,X5R,602433-112	C4P2,C4P3,C4P4,C4P5,C4P7,C5P10,C5P11,C5P12,C5P13,C5P18,C5P19,C5P20,C5P21,C5P28,C5P29,C5P30,C5P31,C7P4,C7P5,C7P6,C7P7,C7P8,C7P9,C7P10,C7P11,C7P13,C7P14,C7P15,C8P8,C8P9,C8P14,C8P15,C8P22,C8P23	34	602433-112	X5R	?	?	?	?	PWR_MCP_CAP	?
CAP_0805-100UF,4V,20%,X5R,602433-112	C4W5,C5L4,C5L5,C5U12,C5U16,C6W11,C6W12,C6W13,C8L3,C8L4,C8T3,C8U10,C8W3,C8W4	14	602433-112	X5R	?	?	?	?	PWR_MLCC_CAP	?
CAP_0805-10UF,16V,10%,EMPTY,C95333-007	C1W17	1	C95333-007	EMPTY	?	?	?	?	?	?
CAP_0805-10UF,16V,10%,X6S,C95333-007	C1B18,C1E21,C1M26,C1M27,C2T22,C2U1,C2U2,C3L2,C3L4,C3L7,C3L8,C3L9,C3L10,C3L11,C3L12,C3L13,C3L15,C3L16,C3L17,C3M8,C3M15,C3M16,C3N33,C3N34,C3N36,C3T8,C3T12,C3T14,C3U2,C3U3,C3U4,C3U6,C3U7,C3U9,C4A19,C4G2,C6L10,C6M3,C6M5,C6N2,C6N3,C6N6,C6N8,C6N10,C6N11,C6P7,C6P13,C6P15,C6P17,C6P19,C6P20,C6P22,C6P24,C6R4,C6R6,C6R8,C6R10,C6R11,C6R13,C6R14,C6U4,C6U7,C6U8,C7B5,C7E6,C7E8,C7F5,C8B6,C8B12,C9B1,C9B2,C9L5,C9L6,C9L10,C9L11,C9L13,C9L14,C9M4,C9M10,C9N13,C9N19,C9N21,C9N25,C9N26,C9N27,C9P1,C9P2,C9P4,C9P7,C9P9,C9P22,C9P24,C9P25,C9P26,C9R7,C9R10,C9R11,C9T4,C9T6,C9T9,C9U3,C9U4,C9U6,C10W1,C25W46	105	C95333-007	X6S	?	?	?	?	?	?
CAP_0805-10UF,16V,10%,X6S,C95333-007	C1E12,C1E15,C9R5	3	C95333-007	X6S	NOPOP	?	?	?	?	?
CAP_0805-10UF,16V,10%,X7R,G10601-001	C1A4,C1A16,C1B7,C3D22,C4A4,C4A17,C4B11,C6T2,C6U10,C6U18,C9T8,C9U8,C9U11	13	G10601-001	X7R	?	?	?	?	?	?
CAP_0805-22UF,6.3V,20%,X6S,C95333-008	C2L45,C2T6,C2T7,C2T9,C8A14	5	C95333-008	X6S	?	?	?	?	?	?
CAP_0805-47UF,4V,20%,X6S,C95333-006	C2L32,C2M11,C2M17,C7A31,C7A32,C7A33,C7B4,C8A12,C8A13,C8B15,C8B16	11	C95333-006	X6S	?	?	?	?	?	?
CAP_0805-47UF,4V,20%,X6S,C95333-006	C3T7,C3T9,C4B2,C4B3,C4P1,C4P9,C4P10,C5P14,C5P15,C5P16,C5P17,C5P22,C5P23,C5P24,C5P25,C5P26,C5P27,C5P32,C5P33,C5P34,C5P35,C5P36,C5P37,C5P40,C6B3,C6U2,C6U3,C7B7,C7P3,C7P17,C7P18,C7P19,C8P10,C8P11,C8P12,C8P13,C8P16,C8P17,C8P18,C8P19,C8P20,C8P21,C8P24,C8P25,C8P26,C8P27,C8P28,C8P29	48	C95333-006	X6S	?	?	?	?	PWR_MLCC_CAP	?
CAP_0805-47UF,4V,20%,X6S,C95333-006	C5G21,C5G22,C5G77,C5G78,C5G115,C5G116,C5G117,C5G118	8	C95333-006	X6S	NOPOP	?	?	?	PWR_MLCC_CAP	?
CAP_0805LF-22UF,4V,20%,X6S,C95333-002	C1A1,C1G20,C6A4,C7G27	4	C95333-002	X6S	?	?	?	NOPOP	PWR_MLCC_CAP	?
CAP_0805LF-22UF,4V,20%,X6S,C95333-002	C1A12,C1G17,C4A1,C4A13,C4G20,C4G24,C5P7,C5P8,C5P9,C6A1,C6G3,C8P5,C8P6,C8P7	14	C95333-002	X6S	?	?	?	?	PWR_MLCC_CAP	?
CAP_0805LF-22UF,4V,20%,X6S,C95333-002	C7A30,C7A42,C9F4,C9F13,C9W13	5	C95333-002	X6S	?	?	?	?	?	?
CAP_1206-0.068UF,50V,20%,X7R,108427-047	C1E2	1	108427-047	X7R	?	?	?	?	?	?
CAP_1206LF-22UF,16V,10%,X6S,D38464-005	C2P10,C7E11,C8E10	3	D38464-005	X6S	?	?	?	?	?	?
CAP_A_0402V-0.01UF,25V,10%,X7R,A36096-045	C1A5,C1A17,C1B9,C1B15,C1F9,C1F19,C1F22,C1G8,C1G10,C1G18,C1G19,C1M30,C1M36,C2L3,C2L4,C2L5,C2L6,C2L7,C2L9,C2L10,C2L12,C2L13,C2L14,C2L15,C2L16,C2L17,C2L18,C2L19,C2L20,C2L21,C2L22,C2L23,C2L24,C2L26,C2L27,C2L37,C2L38,C2L39,C2L40,C2L41,C2L42,C2L43,C2L44,C2L47,C2L48,C2L49,C2L50,C2L51,C2L52,C2P8,C2T18,C2T27,C2T37,C4A5,C4A18,C4B12,C4F9,C4F10,C4G1,C4G3,C4G17,C4G19,C6L1,C6L2,C6L6,C6L7,C6M1,C6M2,C6T1,C6U9,C6U17,C7F1,C8F5,C8W6,C9L1,C9L3,C9L7,C9L8,C9M1,C9M2,C9T7,C9U7,C9U10,C10W3,C10W5,C25W11,CN8F2	87	A36096-045	X7R	?	?	?	?	?	?
CAP_A_0402V-0.01UF,25V,10%,X7R,A36096-045	C1L20,C1M28,C1M31,C1M34,C1M35	5	A36096-045	X7R	?	?	?	?	MCP	?
CAP_A_0402V-0.01UF,25V,10%,X7R,A36096-045	C25W10	1	A36096-045	X7R	NOPOP	?	?	?	?	?
CAP_A_0402V-0.01UF,25V,10%,X7R,A36096-045	C3T5	1	A36096-045	X7R	?	?	?	?	NI_BIOS_ROM2	?
CAP_A_0402V-0.01UF,25V,10%,X7R,A36096-045	C8F6,C8F11,C8F13,C8F15	4	A36096-045	X7R	?	?	?	?	M2_SATA	?
CAP_A_0402V-0.1UF,16V,10%,EMPTY,A36096-030	C1D22,C3D27,C3P1,C9P12,C9P16,C9P17	6	A36096-030	EMPTY	?	?	?	?	?	?
CAP_A_0402V-0.1UF,16V,10%,X7R,A36096-030	C1A10,C1A20,C1B2,C1B5,C1B19,C1C8,C1C9,C1C14,C1C17,C1C25,C1D9,C1D11,C1D13,C1D21,C1D26,C1D27,C1D28,C1D34,C1E14,C1E20,C1E22,C1F28,C1G14,C1G22,C1G25,C1L4,C1L8,C1L9,C1L11,C1L16,C1L17,C1M20,C1M22,C1M23,C1M24,C1M38,C1R27,C1R28,C1T10,C1T11,C1T56,C1U22,C1W18,C1W19,C2L11,C2P1,C2P2,C2P3,C2P4,C2P5,C2P6,C2P7,C2P9,C2P11,C2P12,C2P13,C2P14,C2P15,C2P16,C2R1,C2R2,C2R3,C2R4,C2R5,C2R15,C2R16,C2R17,C2R18,C2T1,C2T2,C2T3,C2T4,C2T5,C2T8,C2T12,C2T15,C2T16,C2T17,C2T21,C2T24,C2T25,C2T26,C2T29,C2T30,C2T32,C2T34,C2T35,C2T36,C2U19,C2U20,C2U21,C2U22,C2U23,C2U24,C2U25,C2U27,C2U28,C3B4,C3B5,C3F2,C3N29,C3P2,C3P5,C3P7,C3P43,C3P44,C3P46,C3P47,C3P48,C3P49,C3P51,C3P52,C3R1,C3R2,C3R3,C3W2,C4A20,C4C10,C4C19,C4D11,C4D19,C4D20,C4D22,C4D24,C4D26,C4D32,C4D35,C4D38,C4D40,C4D49,C4E13,C4E20,C4G22,C4G25,C6F1,C6F2,C6F3,C6P4,C6P5,C6P6,C6P9,C6P10,C6P11,C6P12,C6U5,C6W1,C6W2,C6W3,C6W4,C6W10,C6W14,C7A5,C7A20,C7A38,C7A39,C7A40,C7B2,C7B6,C7C11,C7D1,C7D5,C7E1,C7E2,C7E3,C7E4,C7E5,C7E9,C7F6,C7F15,C7F17,C7G29,C7G36,C7W1,C8A3,C8A8,C8B5,C8B7,C8B8,C8C12,C8C13,C8C14,C8C15,C8D1,C8D2,C8D4,C8E1,C8E2,C8E3,C8E5,C8E8,C8E18,C8E19,C8F16,C8F17,C8W2,C9A1,C9A2,C9A3,C9A4,C9A5,C9B7,C9B10,C9F5,C9F23,C9M5,C9M6,C9M7,C9M8,C9M9,C9P6,C9P11,C9P15,C9R13,C9R14,C9W5,C9W7,C9W8,C10W2,C10W4,C14W1,C14W2,C25W7,C25W8,C25W9,C25W13,C25W14,C25W15,C25W22,C25W31,C25W34,C25W38,C25W45,C25W49,C25W55,C25W58,C25W61,C25W68,C25W93,C25W95,C25W96,C25W97,C25W99,C25W100,C25W101,C30W1,C30W2,C32W1,C32W2,C32W3,C32W4	250	A36096-030	X7R	?	?	?	?	?	?
CAP_A_0402V-0.1UF,16V,10%,X7R,A36096-030	C1E16,C1E17,C1M33,C4R2,C6M6,C9R6,C9R12,CT1,CT6,CT7,CT13,CT16,CT21,CT24,CT25,CT30,CT36,CT39,CT40,CT45,CT51,CT57,CT60,CT63,CT66,CT67,CT70	27	A36096-030	X7R	NOPOP	?	?	?	?	?
CAP_A_0402V-0.1UF,16V,10%,X7R,A36096-030	C1M29	1	A36096-030	X7R	?	?	?	?	MCP	?
CAP_A_0402V-0.1UF,16V,10%,X7R,A36096-030	C1R14,C1R15,C1R18,C1R19,C1R20,C1R21,C1R24,C1R25,C1R26,C1R29,C1R31,C1T3,C1T5,C2M23,C2M24,C9E4,C9E5,C9G4,C9G6	19	A36096-030	X7R	?	?	?	?	NI_I210&RJ45	?
CAP_A_0402V-0.1UF,16V,10%,X7R,A36096-030	C2M3,C2M4,C25P80,C25P83,C25W20,C25W21,C25W90	7	A36096-030	X7R	?	?	?	?	AST2500	?
CAP_A_0402V-0.1UF,16V,10%,X7R,A36096-030	CT12,CT31,CT46,CT52	4	A36096-030	X7R	NOPOP	?	?	NOPOP	?	?
CAP_A_0402V-1.0UF,6.3V,10%,X6S,D97712-004	C1B3,C1B6,C1C7,C1C13,C1G23,C1G27,C1L5,C1L10,C1L18,C1M3,C1M21,C1M25,C1M37,C1T21,C2L8,C2M6,C2M7,C2M8,C2M9,C2M16,C2M18,C2M19,C2M20,C2M21,C2M22,C2M25,C2N2,C2N3,C2N4,C2N5,C2N7,C2N8,C2N9,C2N11,C2N12,C2N13,C2N15,C2N16,C2N18,C2N19,C2N20,C2N25,C2N26,C2R12,C2T19,C2T28,C2T31,C2T33,C2T38,C2U26,C3M19,C3M20,C3M21,C3M22,C3M27,C3M29,C3M30,C3M31,C3M38,C3M39,C3M42,C3M43,C3N1,C3N2,C3N3,C3N4,C3N5,C3N6,C3N7,C3N15,C3N16,C3N17,C3N18,C3N19,C3N20,C3N21,C3N22,C3N23,C3N25,C3N32,C3P3,C3P4,C3P42,C4C3,C4D15,C4D23,C4D25,C4D27,C4D31,C4D36,C7A37,C7B1,C7C19,C7F2,C7F16,C7F18,C8A7,C8F4,C8W5,C9A6,C25W12,C25W91,CN8F1	103	D97712-004	X6S	?	?	?	?	?	?
CAP_A_0402V-1.0UF,6.3V,10%,X6S,D97712-004	C1M32	1	D97712-004	X6S	?	?	?	?	MCP	?
CAP_A_0402V-1.0UF,6.3V,10%,X6S,D97712-004	C3C1,C3C2,C3M46,C3N40,C4F1,C4F3,C4T1,C4T2	8	D97712-004	X6S	?	?	?	?	PWR_MCP_CAP	?
CAP_A_0402V-1.0UF,6.3V,10%,X6S,D97712-004	C3T4	1	D97712-004	X6S	?	?	?	?	NI_BIOS_ROM2	?
CAP_A_0603V-22.0UF,4V,20%,EMPTY,E15431-004	C9E1,C9E12	2	E15431-004	EMPTY	?	?	?	?	NI_I210&RJ45	?
CAP_A_0603V-22.0UF,4V,20%,X6S,E15431-004	C1C19,C1D3,C1D14,C1D24,C1E3,C1E9,C2D1,C2D2,C2D3,C2D4,C2D5,C2D6,C2D7,C2D12,C2D13,C2D14,C2D15,C2D16,C2D17,C2D19,C2D20,C2D21,C2D22,C2D23,C2D24,C2D25,C2D26,C2D27,C2D30,C2D31,C2D32,C2D33,C2D34,C2D35,C2D36,C2D37,C2D38,C2D41,C2D42,C2D43,C2D44,C2D45,C2D46,C2D47,C3D1,C3D2,C3D8,C3D9,C3D15,C3D16,C3D23,C3D24,C3D25,C3E1,C4D4,C4D12,C4D34,C4E3,C4E11,C4P6,C4P8,C5D1,C5D2,C5D3,C5D4,C5D5,C5D6,C5D7,C5D8,C5D9,C5D14,C5D15,C5D16,C5D17,C5D18,C5D19,C5D24,C5D25,C5D26,C5D27,C5D28,C5D29,C5D30,C5D31,C5D32,C5D39,C5D40,C5D41,C5D42,C5D43,C5D44,C5D45,C5D46,C5D47,C5D54,C5D55,C5D56,C5D57,C5D58,C5D59,C5D60,C5D61,C6D3,C6D4,C6D6,C6D7,C6D9,C6D10,C6P3,C6P16,C6P21,C6R2,C6R7,C7C6,C7C10,C7P12,C7P16,C7R1,C9N22,C9P3,C9P10,C9P20,C9R2,C9R8	124	E15431-004	X6S	?	?	?	?	PWR_MLCC_CAP	?
CAP_A_0603V-22.0UF,4V,20%,X6S,E15431-004	C2D18,C2D28,C2D29,C2D39,C2D40,C3D4,C3D5,C3D6,C3D7,C3D10,C3D11,C3D12,C3D13,C3D14,C3D17,C3D18,C3D19,C3D20,C3D21,C3W3,C3W4,C5D20,C5D21,C5D22,C5D23,C5D33,C5D34,C5D35,C5D36,C5D37,C5D38,C5D48,C5D49,C5D50,C5D51,C5D52,C5D53,C5W1,C5W2,C6D2,C6D5,C6D8	42	E15431-004	X6S	?	?	?	?	PWR_MCP_CAP	?
CAP_A_0603V-22.0UF,4V,20%,X6S,E15431-004	C2M1,C2M2,C2M12,C2M13,C2N10,C3L22,C3L23,C3L24,C3L25,C3L26,C3L27,C3M6,C3M7,C3N10,C3N11,C3N12,C3N24,C3N27,C3N28,C3N30,C3N31,C4C11,C6N7,C7A36,C7B15,C7B16,C7B17,C7B18,C7B19,C7B20,C7B21,C7B22,C7B23,C7B24,C7C9,C7D3,C8B1,C8B2,C8B3,C8B4,C8B9,C8B10,C8B11,C8B13,C8B14	45	E15431-004	X6S	?	?	?	?	?	?
CAP_A_0603V-22.0UF,4V,20%,X6S,E15431-004	C5G41,C5G42,C5G43,C5G44,C5G45,C5G46,C5G47,C5G48,C5G49,C5G50,C5G51,C5G52,C5G53,C5G54,C5G55,C5G56,C5G57,C5G58,C5G59,C5G60,C5G61,C5G62,C5G63,C5G64,C5G65,C5G66,C5G67,C5G68,C5G69,C5G70,C5G71,C5G72,C5G73,C5G74,C5G75,C5G76,C5G79,C5G80,C5G81,C5G82,C5G83,C5G84,C5G85,C5G86,C5G87,C5G88,C5G89,C5G90,C5G91,C5G92,C5G93,C5G94,C5G95,C5G96,C5G97,C5G98,C5G99,C5G100,C5G101,C5G102,C5G103,C5G104,C5G105,C5G106,C5G107,C5G108,C5G109,C5G110,C5G111,C5G112,C5G113,C5G114	72	E15431-004	X6S	?	?	NOPOP	?	PWR_MLCC_CAP	?
CAP_A_0603V-22.0UF,4V,20%,X6S,E15431-004	C9W16,C9W19	2	E15431-004	X6S	NOPOP	?	?	?	?	?
CAP_A_0603V-47UF,4V,20%,X5R,602433-106	C2A1,C2A2,C2A3,C2A4,C2A6,C2A7,C2A9,C2A10,C2A11,C2A12,C2A13,C2A14,C2A15,C2G1,C2G2,C2G3,C2G4,C2G5,C2G6,C2G9,C2G10,C2G11,C2G12,C2G13,C2G14,C3A1,C3A2,C3A5,C3A6,C3G1,C3G2,C3G5,C3G6,C4M2,C5A1,C5A2,C5A3,C5A4,C5A6,C5A7,C5A8,C5A9,C5A11,C5A12,C5A13,C5A14,C5A15,C5A16,C5A17,C5A18,C5A19,C5G1,C5G2,C5G3,C5G4,C5G5,C5G6,C5G7,C5G8,C5G11,C5G12,C5G13,C5G14,C5G15,C5G16,C5G17,C5G18,C5L6,C5L7,C5L8,C5L9,C5L10,C5L11,C5L12,C5L13,C5M1,C5M2,C5M4,C5M5,C5M6,C5M7,C5T5,C5T6,C5T7,C5T8,C5T9,C5T10,C5T11,C5T12,C5U2,C5U3,C5U4,C5U5,C5U6,C5U7,C5U8,C5U9,C7L4,C7L5,C7M1,C7M2,C7T4,C7T5,C7U1,C7U2,C8L5,C8L6,C8L7,C8L8,C8L9,C8L10,C8M1,C8M3,C8M4,C8M5,C8M6,C8T5,C8T6,C8T7,C8T8,C8T9,C8T10,C8U2,C8U3,C8U4,C8U5,C8U6,C8U7	128	602433-106	X5R	?	?	?	E15431-004	PWR_MLCC_CAP	?
CAP_A_0603V-47UF,4V,20%,X5R,602433-106	C2A5,C2B1,C2B2,C2F1,C2G8,C2G15,C5A5,C5B1,C5B2,C5F1,C5F2,C5G10,C5G19,C5L15,C5M3,C5M9,C5M10,C5M11,C5T1,C5T2,C5T13,C5U11,C7M5,C8L12,C8M2,C8M8,C8M9,C8T1,C8T2,C8T11,C8U9,C8U13	32	602433-106	X5R	?	?	?	NOPOP	PWR_MLCC_CAP	?
CAP_A_0603V-47UF,4V,20%,X5R,602433-106	C2F2,C5M13,C5T3,C8M12	4	602433-106	X5R	?	?	?	?	PWR_MLCC_CAP	?
CAP_A_0603V-47UF,4V,20%,X5R,602433-106	C3F1,C3T1,C3T2,C4F2	4	602433-106	X5R	?	?	?	?	PWR_MCP_CAP	?
CAP_A_0603V-47UF,4V,20%,X5R,602433-106	C4M5,C5T4,C8M10,C8T4	4	602433-106	X5R	?	?	?	078.1061T.M001	PWR_MLCC_CAP	?
CHOKE_4PIN_SMLF-90 OHM,IND,752402-015	L1M2	1	752402-015	IND	?	?	?	?	?	?
CHOKE_4PIN_SM_B-67 OHM,EMPTY,752402-028	L30W1,L30W2	2	752402-028	EMPTY	?	?	?	?	?	?
CLX-CONN3A-1-GP_CONN-G3-CLX-CONN3A-1-GP,021.D0139.0103	J1B4	1	021.D0139.0103	?	?	?	?	?	?	?
CONN12_C73564003_PIP-CONN,C73564-003	J7G3,J8G2,J9G1	3	C73564-003	CONN	?	?	?	?	?	?
CONN14_H54902001_PIP-CONN,H54902-001	J9A2	1	H54902-001	CONN	?	?	?	?	?	?
CONN3_C95678002_PIP-CONN,C95678-002	J8C1,J9B2	2	C95678-002	CONN	?	021.60545.0103	?	?	?	?
CONN3_G98259001_PIP-CONN,G98259-001	RM1E1	1	G98259-001	CONN	?	?	?	?	?	?
CONN4_D42317002_PIP-CONN,D42317-002	J9A1	1	D42317-002	CONN	NOPOP	?	?	?	?	?
CONN6_C74770005_PIP-HDR,C74770-005	J1B2	1	C74770-005	HDR	?	?	?	?	?	?
CONN72_G97614002_A_CP-CONN,G97614-002	J8A1	1	G97614-002	CONN	?	?	?	?	?	?
CONN8_C77962004_PIP-CONN,C77962-004	J7G2	1	C77962-004	CONN	?	?	?	?	?	?
CONN8_H62179001_PIP-CONN,H62179-001	J1F3	1	H62179-001	CONN	NOPOP	?	?	?	?	?
CONN9_H51826001_PIP2-CONN,H51826-001	J9B1	1	H51826-001	CONN	?	?	?	?	?	?
CRYSTAL_2013-25.000MHZ,IC,D71700-057	Y9E1	1	D71700-057	IC	?	?	?	?	NI_I210&RJ45	?
CRYSTAL_2013-25.000MHZ,IC,H19611-001	Y8C1	1	H19611-001	IC	?	?	?	?	?	?
CRYSTAL_2013-48.000MHZ,IC,D71700-058	Y7C1	1	D71700-058	IC	?	?	?	?	?	?
CRYSTAL_2013LF-25.000MHZ,IC,D71700-033	Y8F1	1	D71700-033	IC	?	?	?	?	?	?
CRYSTAL_SM-32.768KHZ,IC,C13544-023	Y7C2	1	C13544-023	IC	?	?	?	?	?	?
CSD87384M_SM-IC,H66258-001	EU8E1	1	H66258-001	IC	?	?	?	?	?	?
DIODE2A_DUAL_SMLF-BAS70-05,DIO,C90169-001	CR2U1	1	C90169-001	DIO	?	?	?	?	?	?
DIODEAC_DUAL_ARRAY_SM9-ESD3V3U4ULC,IC,G18435-001	CR1M2,CR30W1	2	G18435-001	IC	?	?	?	?	?	?
DIODEAC_DUAL_ARRAY_SM9-ESD3V3U4ULC,IC,G18435-001	CR25W1,CR25W2	2	G18435-001	IC	?	?	?	?	AST2500	?
DIODE_SM-1N4148W,IC,D89194-001	CR1L1,CR1L2,CR1L3,CR1L4	4	D89194-001	IC	?	?	?	?	?	?
DIODE_SM-MBRS340T3G,EMPTY,C81983-002	CR1F5	1	C81983-002	EMPTY	?	?	?	?	?	?
DIODE_SM-SDMK0340L,EMPTY,H71799-001	CR1B1,CR1E1,CR10W2	3	H71799-001	EMPTY	?	?	?	?	?	?
DIODE_SM-SDMK0340L,IC,H71799-001	CR1B2,CR1F1,CR1F3,CR1F4,CR10W1,CR10W3	6	H71799-001	IC	?	?	?	?	?	?
DIODE_SMLF-1N5819HW,IC,D55839-001	CR3U1	1	D55839-001	IC	?	?	?	?	?	?
DIODE_SMLF-BAT54WS,IC,C73510-001	CR3W1,CR6W1,CR6W2,CR7E1,CR8E1,CR9P2,CR9W1	7	C73510-001	IC	?	?	?	?	?	?
DIODE_SMLF-BAT54WS,IC,C73510-001	CR9P1	1	C73510-001	IC	NOPOP	?	?	?	?	?
DM-FCI-CONN76-8R-GP-U-01_CONN-G4-DM-FCI-CONN76-8R-GP-U-01,ZZ.82092.07601	J1C1,J1F1	2	ZZ.82092.07601	?	?	H22707-001	?	?	?	?
FCI-CONN12-2R-GP_CONN-G5-FCI-CONN12-2R-GP,20.82093.012	J1D1	1	20.82093.012	?	NOPOP	?	?	?	?	?
FCI-CONN12-2R-GP_CONN-G5-FCI-CONN12-2R-GP,20.82093.012	J1E1	1	20.82093.012	?	?	?	?	?	?	?
FERRITE_SM-120,FB,693286-027	FB2M1,FB2M2,FB3M1,FB3M2,FB3M3,FB3M4	6	693286-027	FB	?	?	?	?	?	?
FERRITE_SM-22,FB,656554-051	FB4A1,FB4G1,FB7B1,FB7E1,FB7F1	5	656554-051	FB	?	?	?	?	?	?
FERRITE_SMLF-30,FB,693286-021	FB1U3,FB1U4	2	693286-021	FB	?	?	?	?	?	?
FERRITE_SMLF-600,FB,656554-043	FB2T2,FB6P1	2	656554-043	FB	?	?	?	?	?	?
FET_N_DUAL_SMLF-2N7002DW,FET,D24280-001	Q1D1,Q1L4,Q1W2,Q1W4,Q4W1,Q9P1	6	D24280-001	FET	?	?	?	?	?	?
FET_N_DUAL_SMLF-2N7002DW,FET,D24280-001	Q25W4	1	D24280-001	FET	?	?	?	?	AST2500	?
FET_N_DUAL_SMLF-NTJD4001N,FET,E40049-001	Q1L2,Q2U1,Q3U1,Q4B1,Q4B2,Q4U1,Q7E1,Q7E2,Q7E3,Q7E5,Q7E6,Q9A2,Q9E1,Q9F1,Q9G1	15	E40049-001	FET	?	?	?	?	?	?
FET_N_SOT23LF-2N7002,FET,C79254-001	Q1D2,Q1P2,Q1W1,Q1W5,Q2P1,Q2T2,Q4W2,Q6W1,Q6W4,Q7D1,Q7E4,Q7E8,Q8D2,Q8E1,Q8E2,Q8F2,Q9A3,Q9W1,Q25W5	19	C79254-001	FET	?	?	?	?	?	?
FET_N_SOT23LF-2N7002,FET,C79254-001	Q8F1	1	C79254-001	FET	?	?	?	?	NI_BIOS_ROM2	?
FSA3357_SM-IC,C63273-001	U9F1,U9F2	2	C63273-001	IC	?	?	?	?	?	?
FUSE-3A75V-GP_DISCRET-G5-FUSE-3A75V-GP,69.43001.511	F8B1	1	69.43001.511	?	?	?	?	?	?	?
FUSE_SM-IC,C94311-016	F9B1	1	C94311-016	IC	?	?	?	?	?	?
FUSE_SMT-IC,H45581-001	F1L1	1	H45581-001	IC	?	069.50018.0001	?	?	?	?
GTL2014_SM-IC,D66151-001	U2T4,U3P1,U3P2,U4C2,U7D2,U9G1,U25W10,U25W11	8	D66151-001	IC	?	?	?	?	?	?
H5AN4G6NAFR-TFC-GP_MEMORY-G2-H5AN4G6NAFR-TFC-GP,072.00546.0A0U	U25W5	1	072.00546.0A0U	?	?	?	?	?	?	?
HCB1608KF-800T30-GP_DISCRET-G9-HCB1608KF-800T30-GP,68.00230.231,80OHM@100MHZ,3A,DCR=4MOHM	FB2T1,FB2T3,FB2T4,FB2T5,FB2T7	5	68.00230.231	?	?	?	?	?	?	?
ICS9FGP204_MLFP-IC,E95226-001	EU8F2	1	E95226-001	IC	?	?	?	?	?	?
IND-100NH-35-GP_DISCRET-G8-IND-100NH-35-GP,068.1011N.M001,100NH,ISAT=16A@25C,DCR=0.16MOHM,IRMS=29A@DELTA_T<45C	L1B1,L1F1,L7A5,L7C1,L7F2	5	068.1011N.M001	?	?	?	?	?	?	?
IND-120NH-30-GP_DISCRET-GB2-IND-120NH-30-GP,068.1202N.M001,120NH,ISAT=94A@25C,DCR=0.17MOHM,IRMS=66A@DELTA_T<40C	L1A1,L1F2,L7A3,L7G2	4	068.1202N.M001	?	?	?	068.9002N.1021	NOPOP	?	?
IND-120NH-30-GP_DISCRET-GB2-IND-120NH-30-GP,068.1202N.M001,120NH,ISAT=94A@25C,DCR=0.17MOHM,IRMS=66A@DELTA_T<40C	L1A2,L1G1,L7A1,L7G1	4	068.1202N.M001	?	?	?	068.9002N.1021	068.1202N.M001	?	?
IND-120NH-30-GP_DISCRET-GB2-IND-120NH-30-GP,068.1202N.M001,120NH,ISAT=94A@25C,DCR=0.17MOHM,IRMS=66A@DELTA_T<40C	L1C2,L1D1,L1D2,L1D3,L1E1,L4C3,L4D1,L4D2,L4D3,L4E1	10	068.1202N.M001	?	?	?	?	?	?	?
IND-150NH-56-GP_DISCRET-GA1-IND-150NH-56-GP,068.1512N.M001,150NH,ISAT=75A@25C,DCR=0.17MOHM,IRMS=66A@DELTA_T<40C	L4E2,L7C2	2	068.1512N.M001	?	?	?	?	?	?	?
IND-1UH-361-GP_DISCRET-GC1-IND-1UH-361-GP,068.1R010.1781,1.0UH,ISAT=24A@25C,DCR=4.6MOHM	L8F1	1	068.1R010.1781	?	?	?	?	?	?	?
IND-300NH-20-GP_DISCRET-GB1-IND-300NH-20-GP,068.3012N.M001,300NH,ISAT=33A@25C,DCR=0.17MOHM,IRMS=66A@DELTA_T<40C	L1C1,L4C2,L7A2,L7A4	4	068.3012N.M001	?	?	?	?	?	?	?
IND-68NH-15-GP_DISCRET-GC1-IND-68NH-15-GP,68.6803N.10D,68NH,300MA,DCR=800MOHM	L25W1,L25W2,L25W3	3	68.6803N.10D	?	?	?	?	?	AST2500	?
IND-80NH-1-GP_DISCRET-GC2-IND-80NH-1-GP,068.8001N.M001,80NH,ISAT=50A@25C,DCR=0.22MOHM,IRMS=34A@DELTA_T<45C	L1B2,L4C1	2	068.8001N.M001	?	?	?	?	?	?	?
INDUCTOR_SM-0.47UH,IND,E13358-018	L4A1,L4G1,L7B1,L7F1	4	E13358-018	IND	?	?	?	?	?	?
INDUCTOR_SM-2.2UH,IND,E98761-003	L8E1	1	E98761-003	IND	?	?	?	?	?	?
INDUCTOR_SMT-0.022UH,IND,721891-082	L2M1	1	721891-082	IND	?	?	?	?	?	?
IR354XX_SM-IR35411,IC,H73688-001	EU1A1,EU1F1,EU7A4,EU7G3	4	H73688-001	IC	?	?	?	NOPOP	?	?
IR354XX_SM-IR35411,IC,H73688-001	EU1A2,EU1C3,EU1D1,EU1D3,EU1D4,EU1E2,EU1G1,EU4C2,EU4D1,EU4D3,EU4D6,EU4E1,EU7A1,EU7G2	14	H73688-001	IC	?	?	?	?	?	?
IR354XX_SM-IR35412,IC,H73684-001	EU1C1,EU4C1,EU4E2,EU7A2,EU7A3,EU7C1	6	H73684-001	IC	?	?	?	?	?	?
LBG_CORE_QAT_EXT_D_BGA1-IC,H91415-002	U7C1	1	H91415-002	IC	?	?	?	?	?	?
LCMXO2_A_256BGA-IC,H63395-001	U8D7	1	H63395-001	IC	?	?	?	?	?	?
LED_1NC-BLUE,IC,C96565-012	DS9A1	1	C96565-012	IC	?	?	?	?	?	?
LED_1NCLF-GREEN,IC,C96565-011	DS9A2	1	C96565-011	IC	?	?	?	?	?	?
LED_1NCLF-YELLOW,IC,C96565-003	DS9A3	1	C96565-003	IC	?	?	?	?	?	?
LED_A1-RED,IC,D14725-005	DS9F1	1	D14725-005	IC	?	?	?	?	?	?
LED_A1LF-GREEN,IC,C97278-010	DS9A5,DS9A6,DS9E1	3	C97278-010	IC	?	?	?	?	?	?
LED_A1LF-GREEN,IC,D14725-022	DS9A4,DS9A7	2	D14725-022	IC	?	?	?	?	?	?
LMV331IDCKRG4-GP_DISCRET-G-LMV331IDCKRG4-GP,74.00331.A2F	Q9W4	1	74.00331.A2F	?	?	?	?	?	?	?
LMV431AIMFX-GP_DISCRET-G5-LMV431AIMFX-GP,74.MV431.031	VR32W1	1	74.MV431.031	?	?	?	?	?	?	?
LOTES-CON4-S1-GP_CONN-G7-LOTES-CON4-S1-GP,021.60521.0104	J1F2,J10W1	2	021.60521.0104	?	?	?	?	?	?	?
M25PE16_SM-IC,H77797-001	U9E1	1	H77797-001	IC	?	?	?	?	NI_I210&RJ45	?
MAX4564EKA-GP_SCRET-GC1-MAX4564EKA-GP,074.04564.0099	U25W13	1	074.04564.0099	?	?	?	?	?	?	?
MIC5166_DFN-IC,H55101-001	EU4A1,EU4A2,EU4G2,EU4G3	4	H55101-001	IC	?	?	?	?	?	?
MOSFETN_1D3S_SOT5-IC,G68777-001	EU1E1,EU1E3,EU9R1	3	G68777-001	IC	?	?	?	?	?	?
MOSFET_N_LCC3-BSZ019N03LS,NFET,G26762-001	Q1B1,Q7E7,Q8B1,Q8G1	4	G26762-001	NFET	?	?	?	?	?	?
MTG_KEYHOLE_TH-EMPTY,NA	TH1A1,TH4A1,TH4G1,TH7A1,TH7G1,TH9A1,TH9G1	7	NA	EMPTY	?	?	?	?	?	?
NB3W1200L_LCC-IC,H13585-001	EU4D2	1	H13585-001	IC	?	?	?	?	?	?
NC7SB3157_SMLF-IC,C99406-001	U1M2,U2M1	2	C99406-001	IC	?	?	?	?	MCP	?
NC7SB3157_SMLF-IC,C99406-001	U1M7,U6W12,U8W2	3	C99406-001	IC	?	?	?	?	?	?
NCP3232L_SM-IC,H86355-001	EU4A3,EU4G1,EU7B1,EU7F1	4	H86355-001	IC	?	?	?	?	?	?
NPN_DUAL_SSOPLF-MBT3904,EMPTY,C52264-001	Q9A1	1	C52264-001	EMPTY	?	?	?	?	?	?
NPN_DUAL_SSOPLF-MBT3904,XSTR,C52264-001	Q8D1,Q8W1	2	C52264-001	XSTR	?	?	?	?	?	?
NPN_SM-MMBT3904,IC,C52245-001	Q1D3,Q1F1,Q1L3,Q1W6,Q2T1,Q6W2,Q9T1,Q9W2,Q9W3	9	C52245-001	IC	?	?	?	?	?	?
OSC_C_6P10-156.25MHZ,OSC,G63831-004	Y3F1,Y6F1	2	G63831-004	OSC	?	?	?	?	?	?
OSC_C_SM4-24MHZ,OSC,D34520-021	Y9F2	1	D34520-021	OSC	?	?	?	?	?	?
PCA9554PWR-GP_DISCRET-G1-PCA9554PWR-GP,71.09554.C0W	U6W11	1	71.09554.C0W	?	?	?	?	?	?	?
PCA9617_SSOP-IC,G81764-001	U1W3,U3B1,U4G1,U6F1,U7E1	5	G81764-001	IC	?	?	?	?	?	?
PI3B3257A_TSSOPLF-IC,E16801-001	U2T1,U8F1	2	E16801-001	IC	?	?	?	?	?	?
PI5A3157BC6E-GP_DISCRET-GC2-PI5A3157BC6E-GP,073.53157.000J	U7W1	1	073.53157.000J	?	?	?	?	?	?	?
PIN-CON3-27-GP_CONN-G7-PIN-CON3-27-GP,021.60545.0103	J8D4	1	021.60545.0103	?	?	?	?	?	?	?
POLYSW-1D1A6V-2-GP-U_DISCRET-G7-POLYSW-1D1A6V-2-GP-U,69.50007.D81	F30W1	1	69.50007.D81	?	?	?	?	?	NO_KR	?
POLYSW-D5A6V-2-GP-U_DISCRET-GA1-POLYSW-D5A6V-2-GP-U,69.50011.051	F25W1	1	69.50011.051	?	?	069.50007.0071	?	?	AST2500	?
PXE1110B_QFN-IC,H89187-001	EU3P1,EU4D5,EU8A1	3	H89187-001	IC	?	?	?	?	?	?
PXE1610B_QFN-IC,H79206-001	EU1C2,EU4D4	2	H79206-001	IC	?	?	?	?	?	?
PXM1310B_QFN-IC,H89186-001	EU1B1,EU1G2,EU7A5,EU7G1	4	H89186-001	IC	?	?	?	?	?	?
RB551V30-GP_DISCRET-G-RB551V30-GP,83.R5003.H8H	D25W8	1	83.R5003.H8H	?	?	?	?	?	AST2500	?
RES_0402-0.0,5%,1/16W,CHIP,G21497-005	R1B10,R1B11,R1C2,R1C3,R1C5,R1C7,R1C14,R1D2,R1D3,R1D24,R1D25,R1D44,R1D45,R1E6,R1E7,R1F8,R1G9,R1G10,R1L6,R1L12,R1M10,R1M13,R1M15,R1M16,R1M17,R1M18,R1R1,R1R8,R1T36,R1T37,R1U8,R1U11,R1U53,R1U54,R1U58,R1U59,R1U60,R1W12,R1W14,R1W15,R1W16,R1W17,R1W18,R1W19,R1W20,R1W21,R1W22,R1W23,R1W24,R1W27,R1W28,R1W29,R1W33,R1W34,R2L14,R2L17,R2N20,R2N21,R2P1,R2P14,R2R4,R2R12,R2T2,R2T17,R2T20,R2T27,R2T32,R2T40,R2T44,R2T60,R2T64,R2T65,R2T66,R2T67,R2T68,R2U37,R2U46,R2U47,R2W3,R2W5,R3B3,R3B5,R3D18,R3F2,R3F4,R3L1,R3L4,R3L6,R3M1,R3M6,R3N7,R3P1,R3P2,R3P3,R3P11,R3P22,R3P26,R3P34,R3P35,R3P58,R3P59,R3T13,R3U6,R4A2,R4A3,R4A8,R4A9,R4B1,R4B3,R4B14,R4C2,R4C4,R4D26,R4D47,R4D54,R4D56,R4D66,R4D67,R4E16,R4E17,R4G4,R4G8,R4G16,R4G23,R4G25,R4T1,R6B4,R6B5,R6F7,R6F9,R6L6,R6L8,R6L10,R6L11,R6N3,R6N11,R6N12,R6P10,R6P18,R6P19,R6P41,R6P47,R6R2,R6R5,R6R6,R6U4,R6U5,R6U6,R6U7,R6W17,R6W18,R7A11,R7A12,R7A18,R7B9,R7B11,R7B20,R7C15,R7D27,R7D28,R7D36,R7D37,R7D39,R7D41,R7E9,R7E13,R7E17,R7E22,R7F9,R7F12,R7F21,R7F35,R7G2,R7G4,R7G14,R7G17,R7G21,R7G114,R7W1,R7W5,R7W8,R7W10,R7W11,R7W12,R7W13,R7W14,R7W16,R7W17,R7W18,R8B12,R8B14,R8C24,R8D35,R8D43,R8E1,R8E21,R8E25,R8E26,R8E27,R8E28,R8E33,R8E35,R8E37,R8E38,R8F2,R8F6,R8F11,R8F38,R8G7,R8G8,R8G10,R8G13,R8G14,R8G17,R8G18,R8G19,R8G21,R8G22,R8W10,R8W11,R8W12,R8W13,R8W14,R9A3,R9A8,R9F27,R9F33,R9F62,R9F64,R9F65,R9F67,R9F69,R9G4,R9G28,R9G29,R9G32,R9G33,R9G34,R9L9,R9M3,R9M9,R9M20,R9M21,R9N3,R9N16,R9P8,R9P15,R9P21,R9P22,R9P32,R9R2,R9R9,R9R10,R9R11,R9R12,R9T1,R9T8,R9U1,R9U7,R9U10,R12W25,R12W28,R12W31,R12W34,R25W59,R25W74,R25W83,R25W118,R25W143,R25W144,R25W145,R25W154,R25W155,R25W181,R25W184,R25W186,R25W187,R30W1,R30W2,R30W3,R30W4,R32W10,R32W11,R32W12	284	G21497-005	CHIP	?	?	?	?	?	?
RES_0402-0.0,5%,1/16W,CHIP,G21497-005	R1M5,R1M6,R1W13,R1W38,R1W39,R2U50,R2W4,R6W19,R7D23,R7W6,R7W9,R7W15,R8W1,R25W182	14	G21497-005	CHIP	NOPOP	?	?	?	?	?
RES_0402-0.0,5%,1/16W,CHIP,G21497-005	R7C2,R7C4,R25W141	3	G21497-005	CHIP	?	?	?	?	AST2500	?
RES_0402-0.0,5%,1/16W,CHIP,G21497-005	R2U14,R2U15,R2U16,R2U17,R2U18,R2U19,R2U20,R2U21,R2U22,R2U23,R2U24,R2U25,R2U26,R2U27,R2U28,R2U29,R760,R767,R768,R769,R771,R774,R775,R777,R778,R779,R780,R781,R782,R783,R784,R785	32	G21497-005	CHIP	?	?	?	?	PCIE_RISER	?
RES_0402-0.0,5%,1/16W,CHIP,G21497-005	R3L8,R3U9,R9L4,R9U12	4	G21497-005	CHIP	?	?	?	NOPOP	?	?
RES_0402-0.0,5%,1/16W,CHIP,G21497-005	R5W1,R5W2,R9B11,R9B13	4	G21497-005	CHIP	?	?	?	?	MCP	?
RES_0402-0.0,5%,1/16W,CHIP,G21497-005	R8F18,R8F21	2	G21497-005	CHIP	?	?	?	?	M2_PCIE	?
RES_0402-0.0,5%,1/16W,CHIP,G21497-005	R9E18,R9E20,R9G9,R9G11,R9G17,R9G18,R9G19,R9G20,R9G22,R9G24	10	G21497-005	CHIP	?	?	?	?	NI_I210&RJ45	?
RES_0402-0.0,5%,1/16W,CHIP,G21497-005	R9P16	1	G21497-005	CHIP	?	?	NOPOP	?	?	?
RES_0402-0.0,5%,1/16W,EMPTY,G21497-005	R1C9,R1C10,R1C11,R1C31,R1F9,R1T15,R1T23,R1T24,R1T35,R1T38,R1U55,R1U56,R1U57,R1U61,R1U62,R1W30,R2P12,R2T57,R2T58,R2T59,R2T61,R2T62,R2T63,R2T69,R2T71,R2U45,R2U49,R2U51,R3D31,R3F1,R3F3,R3F5,R3F6,R3N30,R3P63,R4T2,R4W5,R6D16,R6F6,R6F8,R6F10,R6F11,R7D38,R7D40,R7D43,R7G15,R7G16,R7G18,R7G19,R8C23,R8E11,R8E29,R8F37,R8G9,R8G11,R8G12,R8G15,R8G16,R9E14,R9F24,R9F26,R9F60,R9F63,R9F66,R9F68,R9F70,R9G27,R9G30,R12W26,R12W27,R12W29,R12W30,R12W32,R12W33,R12W35,R12W36,R25W140	77	G21497-005	EMPTY	?	?	?	?	?	?
RES_0402-1.00K,1%,1/16W,CHIP,G21796-026	R1B1,R1B2,R1C28,R1C32,R1C33,R1C36,R1D6,R1D7,R1D8,R1D36,R1E9,R1E10,R1F5,R1F6,R1G2,R1G3,R1G11,R1G15,R1G16,R1G17,R1L13,R1L23,R1L36,R1L38,R1T11,R1T29,R1T30,R1U17,R1U30,R1U63,R1U64,R1W25,R2L18,R2L22,R2M4,R2P2,R2R5,R2T5,R2T7,R2T25,R2T50,R2U43,R3M10,R3P8,R3P18,R3P25,R3P32,R3P36,R3P56,R3R1,R3R2,R3R15,R4B10,R4C8,R4C9,R4D42,R4D49,R4D58,R4E3,R4E4,R4E5,R4F4,R4F5,R4G2,R4G3,R4G14,R4G21,R4G22,R4R1,R4W2,R6L1,R6L2,R6L12,R6L13,R6L16,R6M1,R6N13,R6N14,R6N15,R6P16,R6P20,R6P21,R6P48,R6T5,R6W16,R6W21,R6W23,R7B4,R7B5,R7B17,R7D2,R7D7,R7D18,R7D26,R7E12,R7E20,R7F19,R7F22,R7F27,R7G27,R7G28,R7G29,R7G31,R8A5,R8A6,R8B2,R8B23,R8B30,R8C4,R8C18,R8D21,R8D27,R8D28,R8E2,R8F5,R8W2,R8W3,R8W8,R9A14,R9A15,R9A17,R9B6,R9B8,R9L1,R9L2,R9L6,R9L7,R9L11,R9M1,R9N14,R25W158,R25W159,R25W160,R25W161,R25W166,R25W167,R25W168,R25W169,R25W170,R25W175,R25W176,R25W177,R25W178,R25W179,R25W180	145	G21796-026	CHIP	?	?	?	?	?	?
RES_0402-1.00K,1%,1/16W,CHIP,G21796-026	R1M19,R1M21,R4R6,R6M8,R9B9,R9B12,R9B14	7	G21796-026	CHIP	?	?	?	?	MCP	?
RES_0402-1.00K,1%,1/16W,CHIP,G21796-026	R1M20,R1T10,R1T12	3	G21796-026	CHIP	NOPOP	?	?	?	?	?
RES_0402-1.00K,1%,1/16W,CHIP,G21796-026	R1U15	1	G21796-026	CHIP	?	?	?	?	PD_SKU_ID3	?
RES_0402-1.00K,1%,1/16W,CHIP,G21796-026	R1U16	1	G21796-026	CHIP	?	?	?	?	PD_SKU_ID1	?
RES_0402-1.00K,1%,1/16W,CHIP,G21796-026	R1U18	1	G21796-026	CHIP	?	?	?	?	PD_SKU_ID0	?
RES_0402-1.00K,1%,1/16W,CHIP,G21796-026	R2N18	1	G21796-026	CHIP	?	?	?	?	PD_SKU_ID4	?
RES_0402-1.00K,1%,1/16W,CHIP,G21796-026	R3W1	1	G21796-026	CHIP	?	64.47035.L0L	?	?	?	?
RES_0402-1.00K,1%,1/16W,EMPTY,G21796-026	R1C6,R1E5,R1M23,R2N14,R2N24,R2P11,R2R11,R2T1,R3N15,R3N16,R3N17,R3P5,R3P6,R3P7,R3P64,R4C3,R4E15,R7D1,R7D19,R7E19,R8C17,R8D5,R8E4,R8E6,R8F35,R9A1	26	G21796-026	EMPTY	?	?	?	?	?	?
RES_0402-1.0K,0.1%,1/16W,CHIP,G85996-004	R2M6,R2N4,R2T4,R4B9,R4G10,R7B18,R7F17,R8E18	8	G85996-004	CHIP	?	?	?	?	?	?
RES_0402-1.0K,0.1%,1/16W,CHIP,G85996-004	RF1,RF2,RF3,RF4,RF5,RF7,RF8,RF9,RF10,RF11,RF17,RF19	12	G85996-004	CHIP	?	?	?	?	POWER_FAIR	064.9530D.M001
RES_0402-1.0K,0.1%,1/16W,CHIP,G85996-004	RF12	1	G85996-004	CHIP	?	?	?	?	POWER_FAIR	064.1101D.M001
RES_0402-1.0K,0.1%,1/16W,CHIP,G85996-004	RF6,RF13,RF23,RF24	4	G85996-004	CHIP	?	?	?	?	POWER_FAIR	?
RES_0402-1.0K,0.1%,1/16W,CHIP,G85996-004	RF14,RF15,RF21	3	G85996-004	CHIP	?	?	?	?	POWER_FAIR	064.9090D.M001
RES_0402-1.0K,0.1%,1/16W,CHIP,G85996-004	RF16,RF18,RF20,RF22	4	G85996-004	CHIP	?	?	?	NOPOP	POWER_FAIR	?
RES_0402-1.0M,1%,1/16W,EMPTY,G21796-021	R6L4,R6L5,R6U3,R6U15,R7C11	5	G21796-021	EMPTY	?	?	?	?	?	?
RES_0402-1.37K,1%,1/16W,CHIP,G21796-095	R7E16,R8D15,R8D17,R8W6,R8W7	5	G21796-095	CHIP	?	?	?	?	?	?
RES_0402-1.5K,1%,1/16W,CHIP,G21796-003	R1C16,R2L10,R2M8,R2N29,R3P16,R4D32,R4D57,R32W2	8	G21796-003	CHIP	?	?	?	?	?	?
RES_0402-1.8K,1%,1/16W,CHIP,G21796-336	R5N2,R5N4,R8B6,R8B7,R8B11,R8B13,R8N1,R8N4	8	G21796-336	CHIP	?	?	?	?	?	?
RES_0402-10.0,1%,1/16W,CHIP,G21796-066	R1B16,R1C21,R1D4,R1D46,R1D47,R1D48,R1D51,R1E1,R1G5,R1L2,R1L11,R1L14,R1L18,R1L20,R1L24,R1L25,R1L30,R1L32,R3N9,R3N19,R3R7,R3R14,R4D39,R4E7,R4E8,R4T3,R4T4,R6N8,R6N9,R6T3,R6T4,R6W26,R6W27,R6W36,R6W37,R7A7,R7A14,R7A19,R7G9,R7M3,R7M8,R8A1,R8B20,R9P26,R9P27,R9R4	46	G21796-066	CHIP	?	?	?	?	?	?
RES_0402-10.0,1%,1/16W,EMPTY,G21796-066	R3D32,R5D6	2	G21796-066	EMPTY	?	?	?	?	?	?
RES_0402-10.0K,1%,1/16W,CHIP,G21796-016	R1C34,R1D10,R1D22,R1D23,R1M11,R1M12,R1M24,R1M25,R1T1,R1U6,R1U7,R1W4,R1W7,R2N6,R2N9,R2N13,R2N16,R2N23,R2N28,R2P15,R2P16,R2P18,R2P19,R2P21,R2P22,R2R1,R2R3,R2T22,R2W1,R3N10,R3T14,R3W5,R3W9,R4A5,R4G5,R4G17,R4G18,R4P5,R5N1,R5N3,R5N5,R6F3,R6L9,R6W2,R6W29,R6W39,R6W40,R7B6,R7C5,R7C8,R7C13,R7C20,R7C21,R7C23,R7D4,R7D8,R7D10,R7D12,R7E5,R7E6,R7F1,R7F14,R7F28,R7F32,R7G22,R7G23,R7G26,R7P13,R8B32,R8D16,R8D30,R8D41,R8D44,R8E34,R8F26,R8F36,R8G20,R8N2,R8N3,R8N5,R9E4,R9E13,R9F8,R9F12,R9F13,R9F32,R9F61,R9P5,R9P6,R9P10,R9W1,R9W12,R9W32,R25W79,R25W80,R25W174,WR8D30	97	G21796-016	CHIP	?	?	?	?	?	?
RES_0402-10.0K,1%,1/16W,CHIP,G21796-016	R1D12,R1D19,R9P11	3	G21796-016	CHIP	?	64.1002D.6DL	?	?	?	?
RES_0402-10.0K,1%,1/16W,CHIP,G21796-016	R1R12,R9E1,R9E2,R9E3,R9E22,R9W36	6	G21796-016	CHIP	?	?	?	?	NI_I210&RJ45	?
RES_0402-10.0K,1%,1/16W,CHIP,G21796-016	R2T8,R3T4,R3T12	3	G21796-016	CHIP	?	?	?	?	NI_BIOS_ROM2	?
RES_0402-10.0K,1%,1/16W,CHIP,G21796-016	R32W9	1	G21796-016	CHIP	NOPOP	?	?	?	?	?
RES_0402-10.0K,1%,1/16W,EMPTY,G21796-016	R1E11,R1W26,R2N12,R3P50,R3R11,R3W3,R4D35,R4D38,R7B7,R7B8,R7F30,R7W2,R7W3,R8D13,R8F1,R9P19	16	G21796-016	EMPTY	?	?	?	?	?	?
RES_0402-10.0K,1%,1/16W,EMPTY,G21796-016	R3T9	1	G21796-016	EMPTY	?	?	?	?	NI_BIOS_ROM2	?
RES_0402-100.0,1%,1/16W,CHIP,G21796-017	R1B22,R1C4,R1C12,R1E4,R1E8,R1F2,R1L39,R1L41,R1M3,R1M4,R1U37,R2P20,R2T39,R3B4,R3D3,R3D28,R3E1,R3M11,R3M12,R3N20,R3N21,R3P13,R3P49,R3U2,R4C1,R4C5,R4E14,R4E18,R4P11,R4P12,R4P15,R6B2,R6D1,R6N2,R6P46,R6T8,R6T9,R7A13,R7D32,R7P19,R7P30,R8C21,R8C26,R8D42,R9A9,R9F25,R9N2,R9P1,R9U3,R10W1,R10W6,R25W165	52	G21796-017	CHIP	?	?	?	?	?	?
RES_0402-100.0,1%,1/16W,EMPTY,G21796-017	R1D28,R3L11,R4E10,R4L2,R4U6,R6P35,R7L2,R7U2,R8B15,R9M7	10	G21796-017	EMPTY	?	?	?	?	?	?
RES_0402-100.0K,1%,1/16W,CHIP,G21796-010	R1D11,R1D15,R1D18,R1D32,R1D37,R1D39,R1L9,R1U1,R1U2,R1U4,R1U5,R2L25,R2L26,R3W2,R6W35,R8B4,R9G26,R9P7,R9P23,R9P28,R9P29,R9P33,R25W63,R25W142,R25W157	25	G21796-010	CHIP	?	?	?	?	?	?
RES_0402-100.0K,1%,1/16W,CHIP,G21796-010	R25W60,R25W61,R25W62,R25W64,R25W65	5	G21796-010	CHIP	?	?	?	?	AST2520	?
RES_0402-100.0K,1%,1/16W,CHIP,G21796-010	R3M8,R3M9,R25W66	3	G21796-010	CHIP	NOPOP	?	?	?	?	?
RES_0402-100.0K,1%,1/16W,CHIP,G21796-010	R8D38	1	G21796-010	CHIP	?	64.51135.6DL	?	?	?	?
RES_0402-100.0K,1%,1/16W,CHIP,G21796-160	R1C13,R3P12,R4D27,R4D60,R8A4	5	G21796-160	CHIP	?	?	?	?	?	?
RES_0402-100.0K,1%,1/16W,EMPTY,G21796-010	R3M5,R3P21,R6P40,R7F20,R8A7,R8E40,R9M5,R9U8	8	G21796-010	EMPTY	?	?	?	?	?	?
RES_0402-105.0K,1%,1/16W,CHIP,G21796-099	R1D14	1	G21796-099	CHIP	?	?	64.15435.6DL	64.16535.6DL	?	?
RES_0402-110,1%,1/16W,EMPTY,G21796-203	R6P33	1	G21796-203	EMPTY	?	?	?	?	?	?
RES_0402-113,1%,1/16W,CHIP,G21796-341	R8B9	1	G21796-341	CHIP	?	?	?	?	?	?
RES_0402-11K,1%,1/16W,CHIP,G21796-220	R1D42	1	G21796-220	CHIP	?	?	?	?	?	?
RES_0402-12.1K,1%,1/16W,CHIP,G21796-089	R9P24	1	G21796-089	CHIP	?	?	?	?	?	?
RES_0402-15.0K,1%,1/16W,CHIP,G21796-107	R9P18,R9T6	2	G21796-107	CHIP	?	?	?	?	?	?
RES_0402-150.0,1%,1/16W,CHIP,G21796-009	R1B8,R1D9,R1G7,R1L15,R1L17,R1U35,R1U41,R2T72,R2T73,R2U40,R2U41,R3P15,R4D51,R4E6,R4P17,R4P20,R4P23,R4P24,R4R2,R4R3,R4R4,R6D9,R6T6,R6T7,R7A17,R7G24,R7P5,R7P18,R7P20,R7P21,R7P27,R7P28,R8A13,R8A14,R9A11	35	G21796-009	CHIP	?	?	?	?	?	?
RES_0402-150.0,1%,1/16W,CHIP,G21796-009	R25W123,R25W124,R25W125,R25W126,R25W127,R25W128	6	G21796-009	CHIP	?	?	?	?	AST2500	?
RES_0402-150.0,1%,1/16W,CHIP,G21796-009	R9G1	1	G21796-009	CHIP	?	?	?	?	NI_I210&RJ45	?
RES_0402-150.0K,1%,1/16W,CHIP,G21796-109	R9P17	1	G21796-109	CHIP	?	?	?	?	?	?
RES_0402-169,1.0%,1/16W,CHIP,G21796-276	R3N1	1	G21796-276	CHIP	?	?	?	?	?	?
RES_0402-16K,1.0%,1/16W,CHIP,G21796-317	R1B12,R1D34,R7A10	3	G21796-317	CHIP	?	?	?	?	?	?
RES_0402-16K,1.0%,1/16W,CHIP,G21796-317	R3N29	1	G21796-317	CHIP	?	?	?	?	MCP	?
RES_0402-2,1.0%,1/16W,CHIP,G21796-274	R1F4,R1G1,R1G14,R4F3,R4G1,R4G20,R6L3,R6L14,R6M2,R9L3,R9L8,R9M2	12	G21796-274	CHIP	?	?	?	?	?	?
RES_0402-2.0K,1%,1/16W,CHIP,G21796-001	R2L4,R2L5,R2L6,R2L11,R2L12,R2L15,R2L21,R2L23,R3N3,R8C15,R8C16,R9M16,R9M17,R9W16,R9W17,R32W5,R32W6,R32W7	18	G21796-001	CHIP	?	?	?	?	?	?
RES_0402-2.0K,1%,1/16W,EMPTY,G21796-001	R6P32,R6P37	2	G21796-001	EMPTY	?	?	?	?	?	?
RES_0402-2.2,5%,1/16W,EMPTY,G21497-016	R4A7,R4F6,R7A15,R7F7,R8F3	5	G21497-016	EMPTY	?	?	?	?	?	?
RES_0402-2.21K,1%,1/16W,CHIP,G21796-112	R1R16,R1R17,R1R18,R1R19,R1R20,R1R21,R1R22,R1R23,R2T29,R4U2,R8F23,R9A7,R9A12,R9A16	14	G21796-112	CHIP	?	?	?	?	?	?
RES_0402-2.26K,1.0%,1/16W,CHIP,G21796-311	R1B13,R1G6,R2U5,R2U13,R3P61,R7A8,R7A9,R7D5,R7D9,R7F36,R7G10	11	G21796-311	CHIP	?	?	?	?	?	?
RES_0402-2.26K,1.0%,1/16W,CHIP,G21796-311	R7G8	1	G21796-311	CHIP	NOPOP	?	?	?	?	?
RES_0402-2.26K,1.0%,1/16W,EMPTY,G21796-311	R1C18,R1D53,R2L24,R3N23,R4D31,R4E20,R6P49,R8G3,R8G6	9	G21796-311	EMPTY	?	?	?	?	?	?
RES_0402-2.67K,1%,1/16W,CHIP,G21796-180	R8A2	1	G21796-180	CHIP	?	?	?	?	?	?
RES_0402-2.7K,1%,1/16W,CHIP,G21796-344	R1T4,R1T6,R1U49,R9G35,R9P4,R9P20,R25W30	7	G21796-344	CHIP	?	?	?	?	?	?
RES_0402-2.7K,1%,1/16W,CHIP,G21796-344	R1U21	1	G21796-344	CHIP	?	?	?	?	PU_SKU_ID3	?
RES_0402-2.7K,1%,1/16W,CHIP,G21796-344	R1U22	1	G21796-344	CHIP	?	?	?	?	PU_SKU_ID1	?
RES_0402-2.7K,1%,1/16W,CHIP,G21796-344	R1U23	1	G21796-344	CHIP	?	?	?	?	PU_SKU_ID0	?
RES_0402-2.7K,1%,1/16W,CHIP,G21796-344	R1U24	1	G21796-344	CHIP	NOPOP	?	?	?	?	?
RES_0402-2.7K,1%,1/16W,CHIP,G21796-344	R2N17	1	G21796-344	CHIP	?	?	?	?	PU_SKU_ID4	?
RES_0402-2.7K,1%,1/16W,EMPTY,G21796-344	R1T5	1	G21796-344	EMPTY	?	?	?	?	?	?
RES_0402-20.0,1%,1/16W,CHIP,G21796-173	R1M8,R1M9,R1T7,R1T8,R1U9,R1U10,R1U19,R1U20,R2T49,R2U1,R2U6,R2U7,R2U9,R2U10,R2U31,R2U32,R2U33,R2U34,R3R8,R3R9,R4T9,R4T10,R6U13,R6U14,R6W20,R6W22,R7M4,R7M5,R8C11,R8C12,R8C14,R8C20,R8D4,R8D7,R8D23,R8D24,R8G4,R8G5,R8W4,R8W5,R9F22,R9F23,R9G12,R9G13,R9G14,R9G15,R9M13,R9M14,R9R7,R9R8,R9W13,R9W14,R25W121,R25W122	54	G21796-173	CHIP	?	?	?	?	?	?
RES_0402-20.0,1%,1/16W,EMPTY,G21796-173	R2U8,R2U12,R2U35,R2U36	4	G21796-173	EMPTY	?	?	?	?	?	?
RES_0402-20.0K,1%,1/16W,CHIP,G21796-040	R1R7	1	G21796-040	CHIP	?	?	?	?	NI_I210&RJ45	?
RES_0402-20.0K,1%,1/16W,CHIP,G21796-040	R3N4,R4B5,R4G7,R6W38,R7B15,R7C10,R7F13,R8D40,R8E16,R9A5	10	G21796-040	CHIP	?	?	?	?	?	?
RES_0402-200.0,1%,1/16W,CHIP,G21796-004	R1L22,R1L31,R1M14,R2R9,R2T19,R2T26,R2T37,R9E10,R9E11,R9E12	10	G21796-004	CHIP	?	?	?	?	?	?
RES_0402-200.0,1%,1/16W,CHIP,G21796-004	R2T13	1	G21796-004	CHIP	?	?	?	?	NI_BIOS_ROM2	?
RES_0402-200.0K,1%,1/16W,CHIP,G21796-080	R1D20	1	G21796-080	CHIP	?	?	64.16935.6DL	?	?	?
RES_0402-200.0K,1%,1/16W,CHIP,G21796-080	R1U50	1	G21796-080	CHIP	?	?	?	?	?	?
RES_0402-22.1,1.0%,1/16W,CHIP,G21796-250	R1B5,R1G12,R3M3,R7F24	4	G21796-250	CHIP	NOPOP	?	?	?	?	?
RES_0402-22.1,1.0%,1/16W,CHIP,G21796-250	R1C30,R1T9,R1W9,R2L16,R2T41,R2T42,R2T46,R3P20,R4B7,R4D46,R4D63,R4G12,R7B12,R7E15,R7F16,R8A11,R8E7,R8F10,R8G1,R8G24,R9F11,R25W78,R25W85,R25W86,R25W87,R25W88,R25W89,R25W90	28	G21796-250	CHIP	?	?	?	?	?	?
RES_0402-22.1,1.0%,1/16W,CHIP,G21796-250	R8G25,R9E17,R9E19,R9F1	4	G21796-250	CHIP	?	?	?	?	NI_I210&RJ45	?
RES_0402-221,1.0%,1/16W,CHIP,G21796-271	R1C1,R1L33,R2U42,R2U44,R3B1,R6B3,R6N10,R9A20,R9E24,R9F28,R10W4	11	G21796-271	CHIP	?	?	?	?	?	?
RES_0402-23.2K,1%,1/16W,CHIP,G21796-114	R8E31	1	G21796-114	CHIP	?	?	?	?	?	?
RES_0402-24.9K,1%,1/16W,CHIP,G21796-254	R8E39	1	G21796-254	CHIP	?	?	?	?	?	?
RES_0402-240,1.0%,1/16W,CHIP,G21796-294	R1T27,R3D24,R3P60,R3R13,R4C10,R4P14,R4P21,R4T5,R4T6,R5D3,R5D4,R6T1,R6T2,R7M2,R7M7,R7P14,R9M18,R9M19,R9W18,R9W19,R25W117	21	G21796-294	CHIP	?	?	?	?	?	?
RES_0402-240,1.0%,1/16W,EMPTY,G21796-294	R3D12,R3D13,R3D16,R3D17,R3D22,R3D23,R3D25,R3D26,R4P1,R4P6,R4P7,R6D6,R6D7,R6D10,R6D13,R6D14,R6D15,R7P15,R7P22	19	G21796-294	EMPTY	?	?	?	?	?	?
RES_0402-249,0.1%,1/16W,CHIP,G85996-031	R3D27,R5D5	2	G85996-031	CHIP	?	?	?	?	?	?
RES_0402-27.4,1%,1/16W,CHIP,G21796-182	R4D1,R4D2,R4D3,R4D4,R4D5,R4D6,R4D7,R4D8,R4D9,R4D10,R4D11,R4D12,R4D13,R4D14,R4D16,R4D17,R4D19,R4D20,R4D21,R4D22,R4D23,R4D25,R4D28,R4D29	24	G21796-182	CHIP	?	?	?	?	?	?
RES_0402-3.16K,1%,1/16W,CHIP,G21796-043	R1B15,R1G22,R3N31,R4D64,R4E2,R9N7	6	G21796-043	CHIP	?	?	?	?	?	?
RES_0402-3.16K,1%,1/16W,CHIP,G21796-043	R4C11	1	G21796-043	CHIP	?	?	?	?	MCP	?
RES_0402-3.32K,1%,1/16W,CHIP,G21796-027	R1R3,R1R9,R9F5	3	G21796-027	CHIP	?	?	?	?	NI_I210&RJ45	?
RES_0402-3.32K,1%,1/16W,CHIP,G21796-027	R9E7	1	G21796-027	CHIP	?	?	?	?	?	?
RES_0402-3.32K,1%,1/16W,EMPTY,G21796-027	R1C35,R3P54,R25W116,R25W156	4	G21796-027	EMPTY	?	?	?	?	?	?
RES_0402-3.32K,1%,1/16W,EMPTY,G21796-027	R1R6	1	G21796-027	EMPTY	?	?	?	?	NI_I210&RJ45	?
RES_0402-3.3K,5%,1/16W,CHIP,G21497-013	R4W3,R4W4,R8B24,R8B26,R24W1,R24W2,R32W3	7	G21497-013	CHIP	?	?	?	?	?	?
RES_0402-3.48K,1.0%,1/16W,CHIP,G21796-279	R1U27,R1U38	2	G21796-279	CHIP	?	?	?	?	?	?
RES_0402-3.74K,1%,1/16W,CHIP,G21796-059	R9P9	1	G21796-059	CHIP	?	?	?	?	?	?
RES_0402-301.0,1%,1/16W,CHIP,G21796-076	R1L37	1	G21796-076	CHIP	?	?	?	?	?	?
RES_0402-33.0K,5%,1/16W,CHIP,G21497-023	R4U4	1	G21497-023	CHIP	?	?	?	?	?	?
RES_0402-33.2,1%,1/16W,CHIP,G21796-074	R1B4,R1D1,R1D26,R1D30,R1D33,R1G8,R1L26,R1L29,R1U34,R1U36,R1U46,R2M1,R2M3,R2M7,R2N1,R2N26,R2P4,R2R2,R2R10,R2T28,R2T30,R2T33,R2T38,R2T47,R3N24,R3N26,R3P42,R3P43,R3P46,R3R3,R4A4,R4A6,R4D65,R4G15,R4G19,R6P45,R7B1,R7C14,R7C16,R7C26,R7D24,R7D25,R7D29,R7D31,R7D34,R7F3,R7F4,R7F23,R7F29,R7F37,R8D11,R8D22,R8E5,R8E9,R8E10,R8E13,R8E17,R8E20,R8E24,R8F8,R8F12,R8F27,R8F29,R9A13,R9G31,R9P3,R25W68,R25W69,R25W70,R25W72,R25W73,R25W75,R25W81,R25W82,RN8F5	75	G21796-074	CHIP	?	?	?	?	?	?
RES_0402-33.2,1%,1/16W,CHIP,G21796-074	R25W133,R25W136,R25W138,R25W139	4	G21796-074	CHIP	?	?	?	?	AST2500	?
RES_0402-33.2,1%,1/16W,CHIP,G21796-074	R3T1,R3T2,R3T10,R3U1,R8F7	5	G21796-074	CHIP	?	?	?	?	NI_BIOS_ROM2	?
RES_0402-33.2,1%,1/16W,CHIP,G21796-074	R8D36	1	G21796-074	CHIP	NOPOP	?	?	?	?	?
RES_0402-33.2,1%,1/16W,CHIP,G21796-074	R9E5,R9E6,R9E8,R9E9,R9E16	5	G21796-074	CHIP	?	?	?	?	NI_I210&RJ45	?
RES_0402-33.2,1%,1/16W,EMPTY,G21796-074	R9A2,R9F34	2	G21796-074	EMPTY	?	?	?	?	?	?
RES_0402-330,5%,1/16W,CHIP,G21497-028	R1L43,R1L44,R1W31,R1W32	4	G21497-028	CHIP	?	?	?	?	?	?
RES_0402-348,1%,1/16W,CHIP,G21796-340	R7D15	1	G21796-340	CHIP	?	?	?	?	?	?
RES_0402-348,1%,1/16W,EMPTY,G21796-340	R9F20	1	G21796-340	EMPTY	?	?	?	?	?	?
RES_0402-4.02K,1%,1/16W,CHIP,G21796-082	R2L9,R3N22,R6P27,R6P28,R9N8,R32W1	6	G21796-082	CHIP	?	?	?	?	?	?
RES_0402-4.02K,1%,1/16W,CHIP,G21796-082	R7C24	1	G21796-082	CHIP	?	?	?	?	MCP	?
RES_0402-4.75K,1%,1/16W,CHIP,G21796-072	R1B21,R1D21,R1D35,R1E12,R1F1,R1L7,R1L19,R1L27,R1R5,R1W36,R1W37,R1W42,R1W43,R1W44,R1W45,R2M2,R2M5,R2N7,R2N27,R2N32,R2P3,R2P5,R2P8,R2P13,R2P17,R2R7,R2T3,R2T6,R2T34,R2T35,R2U2,R2U4,R2U48,R3N11,R3N12,R3N13,R3P44,R3P53,R3R4,R3R10,R3R16,R3W6,R3W7,R4D40,R4D41,R4D69,R4D70,R4R5,R4U1,R4U3,R4W1,R4W6,R6M4,R6M9,R6P39,R6W1,R6W4,R6W5,R6W6,R6W10,R6W11,R6W12,R6W24,R6W25,R6W28,R6W41,R6W44,R6W45,R6W46,R7C17,R7D3,R7D6,R7D30,R7D42,R7D44,R7E7,R7E10,R7E11,R7E21,R7F5,R7F33,R7G7,R7W19,R7W21,R8B3,R8B5,R8B8,R8B10,R8B16,R8B17,R8B18,R8B19,R8B25,R8B31,R8C1,R8C2,R8C6,R8C7,R8C9,R8C25,R8D14,R8D25,R8D26,R8D29,R8D31,R8D37,R8E3,R8E14,R8E22,R8E23,R8E32,R8F13,R8F14,R8F24,R8F34,R8G2,R8G23,R8W9,R8W15,R9A18,R9A21,R9E21,R9F3,R9F30,R9F52,R9F55,R9T9,R10W2,R10W3,R10W7,R25W94,R25W95,R25W96,R25W100,R25W104,R25W107,R25W109,R25W129,R25W130,R25W146,R25W148,R25W149,R25W150,R25W151,R25W152,R25W153,R25W185,RN8F1,RN8F3	149	G21796-072	CHIP	?	?	?	?	?	?
RES_0402-4.75K,1%,1/16W,CHIP,G21796-072	R1D29,R6W50,R7E18,R7W20,R7W22,R9F29,R9W33,R9W34,R9W35	9	G21796-072	CHIP	NOPOP	?	?	?	?	?
RES_0402-4.75K,1%,1/16W,CHIP,G21796-072	R1W40	1	G21796-072	CHIP	?	?	?	?	KR	?
RES_0402-4.75K,1%,1/16W,CHIP,G21796-072	R1W41	1	G21796-072	CHIP	NOPOP	?	?	?	KR	?
RES_0402-4.75K,1%,1/16W,CHIP,G21796-072	R25W131,R25W132,R25W134,R25W135	4	G21796-072	CHIP	?	?	?	?	AST2500	?
RES_0402-4.75K,1%,1/16W,CHIP,G21796-072	R2T11,R3T5	2	G21796-072	CHIP	?	?	?	?	NI_BIOS_ROM2	?
RES_0402-4.75K,1%,1/16W,EMPTY,G21796-072	R1D27,R1L28,R2N10,R2U30,R3N2,R3P62,R6P22,R6P23,R6W7,R6W8,R6W9,R6W42,R6W43,R6W47,R7F6,R8E12,R8E19,R8F16,R25W97,R25W98,R25W99,R25W101,R25W102,R25W103,R25W105,R25W106,R25W108,R25W110,R25W111,R25W112,R25W113,R25W114,R25W115,R25W119,RN8F2,RN8F4	36	G21796-072	EMPTY	?	?	?	?	?	?
RES_0402-4.75K,1%,1/16W,EMPTY,G21796-072	R3T3	1	G21796-072	EMPTY	?	?	?	?	NI_BIOS_ROM2	?
RES_0402-4.99K,1%,1/16W,CHIP,G21796-013	R9E23	1	G21796-013	CHIP	?	?	?	?	NI_I210&RJ45	?
RES_0402-4.99K,1%,1/16W,CHIP,G21796-013	R9P12	1	G21796-013	CHIP	?	?	?	?	?	?
RES_0402-40.2K,1%,1/16W,CHIP,G21796-133	R1D40,R6W49	2	G21796-133	CHIP	?	?	?	?	?	?
RES_0402-42.2,1.0%,1/16W,EMPTY,G21796-259	R4D18,R4D24,R6P1,R6P2,R6P3,R6P4,R6P5,R6P6,R6P7,R6P8,R6P9,R6P11,R6P12,R6P13,R6P15,R6P17,R7P1,R7P2,R7P3,R7P4,R7P6,R7P7,R7P9,R7P12	24	G21796-259	EMPTY	?	?	?	?	?	?
RES_0402-470.0,5%,1/16W,CHIP,G21497-024	R1L8	1	G21497-024	CHIP	?	?	?	?	?	?
RES_0402-475.0,1%,1/16W,CHIP,G21796-077	R8F25,R9A4	2	G21796-077	CHIP	?	?	?	?	?	?
RES_0402-49.9,1%,1/16W,CHIP,G21796-047	R1L16,R1T28,R1T40,R2N19,R2N22,R2N31,R2T18,R3B2,R3D4,R3D9,R3D15,R3D19,R3D20,R3P17,R3T11,R4P2,R4P3,R4P4,R4P18,R4P19,R5P2,R5P3,R5P4,R5R1,R6B1,R6D2,R6D5,R6D8,R6D11,R6D12,R6F1,R6F2,R6F4,R6F5,R6N1,R7P8,R7P10,R7P11,R7P25,R7P26,R8B29,R8D19,R8D20,R8P1,R8P2,R8P3,R8R1,R9B4,R9B5,R9N1,R9P2,R9R5,R9R6,R9U4	54	G21796-047	CHIP	?	?	?	?	?	?
RES_0402-49.9,1%,1/16W,CHIP,G21796-047	R1M22,R9B10,R25W164	3	G21796-047	CHIP	NOPOP	?	?	?	?	?
RES_0402-49.9,1%,1/16W,EMPTY,G21796-047	R1W35,R2W2,R3L13,R3N14,R3W10,R4E9,R7W4,R8B21,R9M6	9	G21796-047	EMPTY	?	?	?	?	?	?
RES_0402-49.9K,1%,1/16W,CHIP,G21796-048	R2L19,R8D39,R8F9,R25W57	4	G21796-048	CHIP	?	?	?	?	?	?
RES_0402-49.9K,1%,1/16W,CHIP,G21796-048	R32W4	1	G21796-048	CHIP	NOPOP	?	?	?	?	?
RES_0402-5.11K,1%,1/16W,CHIP,G21796-140	R1U26,R1U29,R1U32,R1U39,R1U47,R8A10	6	G21796-140	CHIP	?	?	?	?	?	?
RES_0402-5.36K,1.0%,1/16W,CHIP,G21796-297	R1G23	1	G21796-297	CHIP	NOPOP	?	?	?	?	?
RES_0402-51,5.0%,1/16W,CHIP,G21497-048	R1U12,R1U13,R1U14,R2R6	4	G21497-048	CHIP	?	?	?	?	?	?
RES_0402-51.1,1.0%,1/16W,CHIP,G21796-208	R2N25,R6N4,R7C3,R7P29,R7R1,R8B1,R9N4	7	G21796-208	CHIP	?	?	?	?	?	?
RES_0402-6.19K,1%,1/16W,CHIP,G21796-161	R1D31,R4B4,R4G9,R7B13,R7F11,R9T3	6	G21796-161	CHIP	?	?	?	?	?	?
RES_0402-6.34K,1%,1/16W,CHIP,G21796-146	R3P51	1	G21796-146	CHIP	?	?	?	?	?	?
RES_0402-63.4K,1.0%,1/16W,CHIP,G21796-327	R2L20	1	G21796-327	CHIP	?	?	?	?	?	?
RES_0402-64.9,1.0%,1/16W,CHIP,G21796-298	R1L21	1	G21796-298	CHIP	?	64.12005.6DL	?	?	?	?
RES_0402-64.9,1.0%,1/16W,CHIP,G21796-298	R3D21,R3P29,R3P38,R7M9	4	G21796-298	CHIP	?	?	?	?	?	?
RES_0402-665,1.0%,1/16W,CHIP,G21796-235	R1T2,R1T3,R2N5,R2N8,R2T53,R2T54,R2U3,R2U11,R2U38,R2U39,R3R5,R3R12,R4T7,R4T8,R6U17,R6U18,R7M1,R7M6	18	G21796-235	CHIP	?	?	?	?	?	?
RES_0402-68.1K,1%,1/16W,EMPTY,G21796-187	R1A2,R1G25,R7A21,R7G30	4	G21796-187	EMPTY	?	?	?	NOPOP	?	?
RES_0402-68.1K,1%,1/16W,EMPTY,G21796-187	R1A3,R1C37,R1D52,R1D54,R1D55,R1E13,R1E14,R1G26,R3L14,R3L15,R4C13,R4D68,R4D71,R4D72,R4E19,R4E21,R4E22,R7A20,R7C25,R7G25	20	G21796-187	EMPTY	?	?	?	?	?	?
RES_0402-69.8K,1%,1/16W,CHIP,G21796-007	R1D16	1	G21796-007	CHIP	?	?	64.57625.6DL	?	?	?
RES_0402-7.5K,1%,1/16W,CHIP,G21796-177	R1D43	1	G21796-177	CHIP	?	064.7501D.06DD	?	?	?	?
RES_0402-7.87K,1.0%,1/16W,CHIP,G21796-242	R4B6,R4G11,R7B14,R7F15	4	G21796-242	CHIP	?	64.39015.6DL	?	?	?	?
RES_0402-7.87K,1.0%,1/16W,CHIP,G21796-242	R4B8,R4G13,R7B16,R7F18	4	G21796-242	CHIP	?	?	?	?	?	?
RES_0402-75,1.0%,1/16W,CHIP,G21796-267	R2T16,R2T31,R2T43,R3P41,R7E2	5	G21796-267	CHIP	?	?	?	?	?	?
RES_0402-75,1.0%,1/16W,CHIP,G21796-267	R2T9	1	G21796-267	CHIP	?	?	?	?	NI_BIOS_ROM2	?
RES_0402-75,1.0%,1/16W,CHIP,G21796-267	R9G2,R9G3	2	G21796-267	CHIP	?	?	?	?	NI_I210&RJ45	?
RES_0402-75K,1%,1/16W,CHIP,G21796-224	R7E14	1	G21796-224	CHIP	?	?	?	?	?	?
RES_0402-8.06K,1%,1/16W,CHIP,G21796-078	R4C12	1	G21796-078	CHIP	?	?	?	?	MCP	?
RES_0402-8.2K,1%,1/16W,CHIP,G21796-345	R1T25,R1T26	2	G21796-345	CHIP	?	?	?	?	?	?
RES_0402-8.2K,1%,1/16W,EMPTY,G21796-345	R7D13	1	G21796-345	EMPTY	?	?	?	?	?	?
RES_0402-90.9,1%,1/16W,CHIP,G21796-365	R3D1,R3D2,R4P8,R4P10,R5D1,R5D2,R7P16,R7P17	8	G21796-365	CHIP	?	?	?	?	?	?
RES_0402-90.9K,1%,1/16W,CHIP,G21796-058	R1D13	1	G21796-058	CHIP	?	?	64.68125.6DL	?	?	?
RES_0402-90.9K,1%,1/16W,CHIP,G21796-058	R3P48	1	G21796-058	CHIP	?	?	?	?	?	?
RES_0603-0,5.0%,1/10W,CHIP,G22178-002	R1R15,R1T32,R1T34	3	G22178-002	CHIP	?	?	?	?	NI_I210&RJ45	?
RES_0603-0,5.0%,1/10W,CHIP,G22178-002	R4B13,R4G24,R7B19,R7F8,R25W93,R25W120,RT1,RT3,RT5,RT9,RT11,RT14,RT15,RT17,RT19,RT23,RT25,RT28,RT30,RT33,RT37,RT40,RT41,RT44,RT46,RT47	26	G22178-002	CHIP	?	?	?	?	?	?
RES_0603-0,5.0%,1/10W,CHIP,G22178-002	RT8,RT21,RT31,RT36	4	G22178-002	CHIP	?	?	?	NOPOP	?	?
RES_0603-0,5.0%,1/10W,EMPTY,G22178-002	R1T33	1	G22178-002	EMPTY	?	?	?	?	NI_I210&RJ45	?
RES_0603-10.0,1%,1/10W,CHIP,G22026-041	R2L8,R9P30	2	G22026-041	CHIP	?	?	?	?	?	?
RES_0603-100.0,1%,1/10W,CHIP,G22026-038	R1E3,R4E13	2	G22026-038	CHIP	?	?	?	?	?	?
RES_0603-100.0K,1%,1/10W,CHIP,G22026-050	R5P1,R6W30,R12W4,R12W9,R12W14,R12W19,RT8P1	7	G22026-050	CHIP	?	?	?	?	?	?
RES_0603-10M,1.0%,1/10W,CHIP,G22026-112	R7C6	1	G22026-112	CHIP	?	?	?	?	?	?
RES_0603-120.0,1%,1/10W,CHIP,G22026-003	R1A1,R1G20,R3U4,R4B2,R4G6,R4L4,R7B10,R7F10	8	G22026-003	CHIP	?	?	?	?	?	?
RES_0603-2.2,1.0%,1/10W,CHIP,G22026-127	R2T21,R2T23,R2T52,R3D14,R6P25	5	G22026-127	CHIP	?	?	?	?	?	?
RES_0603-200K,0.1%,1/10W,CHIP,G22369-010	R7C1	1	G22369-010	CHIP	?	?	?	?	?	?
RES_0603-475.0,1%,1/10W,CHIP,G22026-030	R8A12	1	G22026-030	CHIP	?	?	?	?	?	?
RES_0805-0.0,5%,1/8W,CHIP,G22179-004	R1D41,R1W10,R10W5	3	G22179-004	CHIP	?	?	?	?	?	?
RES_0805-0.0,5%,1/8W,EMPTY,G22179-004	R1W11	1	G22179-004	EMPTY	?	?	?	?	?	?
RES_1206-0.002,1%,1W,CHIP,G52199-004	R1F3,R4B12,R4F2,R9M4	4	G52199-004	CHIP	?	064.R0045.0711	?	?	?	?
RES_PWR_6PAD-0.001,1%,3W,CHIP,E74391-005	R1D49,R9R1	2	E74391-005	CHIP	?	?	064.0U505.0C71	?	?	?
RT8240_QFN-IC,H66262-001	EU8F1	1	H66262-001	IC	?	?	?	?	?	?
RT9059_DFN-IC,H65765-001	EU8A2,EU9F1,EU9F2,EU25F2	4	H65765-001	IC	?	?	?	?	?	?
SC1U10V2KX-4-GP_SMD-BCG6-SC1U10V2KX-4-GP,78.10523.8FL,1UF,10%,10V,0402	C1A11,C1F21,C7A26,C7G42	4	78.10523.8FL	?	?	?	?	NOPOP	?	?
SC1U10V2KX-4-GP_SMD-BCG6-SC1U10V2KX-4-GP,78.10523.8FL,1UF,10%,10V,0402	C1A2,C1C3,C1C18,C1D5,C1D15,C1E6,C1E23,C1G4,C3L1,C3L29,C4C4,C4C14,C4D6,C4D14,C4E6,C4E25,C4E28,C7A18,C7C20,C7G35,C9B9	21	78.10523.8FL	?	?	?	?	?	?	?
SC1U16V3KX-2GP_SMD-BCG-SC1U16V3KX-2GP,78.10521.5BL,1UF,10%,16V,0603,X5R	C8W1,C25W17,C25W18	3	78.10521.5BL	?	?	?	?	?	?	?
SC22P50V2JN-4GP_SMD-BCG-SC22P50V2JN-4GP,78.22034.1FL,22PF,5%,50V,0402,NPO	C9W1,C9W2	2	78.22034.1FL	?	NOPOP	?	?	?	?	?
SC22P50V2JN-4GP_SMD-BCG-SC22P50V2JN-4GP,78.22034.1FL,22PF,5%,50V,0402,NPO	CF1,CF2,CF3,CF4,CF5,CF6,CF7,CF8,CF9,CF10,CF11,CF12,CF13,CF14,CF15,CF17,CF19,CF21,CF23,CF24	20	78.22034.1FL	?	?	?	?	?	POWER_FAIR	?
SC22P50V2JN-4GP_SMD-BCG-SC22P50V2JN-4GP,78.22034.1FL,22PF,5%,50V,0402,NPO	CF16,CF18,CF20,CF22	4	78.22034.1FL	?	?	?	?	NOPOP	POWER_FAIR	?
SC22U16V5MX-4-GP_SMD-BCG5-SC22U16V5MX-4-GP,078.22611.0811,22UF,20%,16V,0805,X6S	C1G2,C4B1,C4E8,C4E9,C4E14,C4G5,C7A13,C7A14,C7B8,C7C7,C7C8,C7E12,C7E13,C7F7,C7W5,C7W6,C7W7,C7W8,C7W9,C7W10,C7W11,C7W12,C7W13,C8E7,C8E9,C8E11,C9F1,C22W1,C22W2,C22W3,C22W4,C22W5,C22W6,C22W7,C22W8,C22W9,C22W10,C22W11,C22W12,C22W13,C22W14,C22W15,C22W16,C22W17,C22W18,C22W19,C22W20,C22W21,C22W22,C22W23,C22W24,C22W25,C22W26,C22W27,C22W28,C22W29,C22W30,C22W31,C22W32,C22W33	60	078.22611.0811	?	?	?	?	?	?	?
SC22U16V5MX-4-GP_SMD-BCG5-SC22U16V5MX-4-GP,078.22611.0811,22UF,20%,16V,0805,X6S	C9E6,C9F2,C22W34,C22W35	4	078.22611.0811	?	NOPOP	?	?	?	NI_I210&RJ45	?
SC22U16V5MX-4-GP_SMD-BCG5-SC22U16V5MX-4-GP,078.22611.0811,22UF,20%,16V,0805,X6S	C30W3,C30W4,C30W5,C30W6,C30W7,C30W8,C30W9	7	078.22611.0811	?	?	?	?	?	NO_KR	?
SC4D7U16V3KX-GP_SMD-BCG5-SC4D7U16V3KX-GP,078.47521.08BD,4.7UF,10%,16V,0603	C2R11	1	078.47521.08BD	?	?	?	?	?	?	?
SCONN10_C12536004_SMLF-CONN,C12536-004	J9B4	1	C12536-004	CONN	?	?	?	?	MCP	?
SCONN11_H67026001_SM-CONN,H67026-001	J8E1	1	H67026-001	CONN	?	?	?	?	?	?
SCONN120_A28699018_SM-SCONN,A28699-018	J9B3	1	A28699-018	SCONN	?	?	?	?	NO_KR	?
SCONN120_H61426002_SM-CONN,H61426-002	J4B2,J4E1,J6B1,J6E1	4	H61426-002	CONN	?	?	?	?	MCP	?
SCONN200_H68296001_SM-CONN,H68296-001	J8G1	1	H68296-001	CONN	?	?	?	?	?	?
SCONN24_H46321001_SM-SCONN,H46321-001	J8B1	1	H46321-001	SCONN	?	?	?	?	?	?
SCONN288_H44441003_PIP-SCONN,H44441-003	J6L1,J6L2,J6M1,J6T1,J6U1,J6U2,J9L1,J9L2,J9M1,J9T1,J9U1,J9U2	12	H44441-003	SCONN	?	?	?	NOPOP	?	?
SCONN288_H44441004_PIP-SCONN,H44441-004	J1A1,J1A2,J1B1,J1G1,J1G2,J1G3,J4A1,J4A2,J4B1,J4G1,J4G2,J4G3	12	H44441-004	SCONN	?	?	?	?	?	?
SCONN60_C21100002_SMLF-CONN,C21100-002	J9A3	1	C21100-002	CONN	?	?	?	?	?	?
SCONN64_H87568002_A_SMT-CONN,H87568-002	J8E4	1	H87568-002	CONN	?	?	?	?	KR	?
SCONN80_E67482007_SM-CONN,E67482-007	J8E3	1	E67482-007	CONN	?	?	?	?	NO_KR	?
SE100U16VM-48-GP_SMD-TCG2-SE100U16VM-48-GP,077.51081.0011	C7W2	1	077.51081.0011	?	?	?	?	?	?	?
SHUNT_SH0201-EMPTY,N_A	SH3D1,SH3D2,SH3P1,SH3P2,SH4L1,SH4L2,SH4U1,SH4U2,SH5L1,SH5U1,SH7L1,SH7L2,SH7U1,SH7U2,SH8L1,SH8U1	16	N_A	EMPTY	?	?	?	?	?	?
SKT-MINI67P-41-GP_SOCKET-G4-SKT-MINI67P-41-GP,062.10003.0B21	J8F1	1	062.10003.0B21	?	?	?	?	?	?	?
SKT-RJ45-LED-XFOR-1-GP_SOCKET-G2-SKT-RJ45-LED-XFOR-1-GP,022.10001.0S51	JA9G1	1	022.10001.0S51	?	?	?	?	?	NI_I210&RJ45	?
SKT-SATA7P-6P-165-GP-U1_SOCKET-G6-SKT-SATA7P-6P-165-GP-U1,022.10014.0121	J2W1	1	022.10014.0121	?	?	?	?	NOPOP	?	?
SKT-SATA7P-6P-165-GP-U1_SOCKET-G6-SKT-SATA7P-6P-165-GP-U1,022.10014.0121	J2W2	1	022.10014.0121	?	?	?	NOPOP	?	?	?
SKT-USB32-8-GP_SOCKET-G4-SKT-USB32-8-GP,062.10009.0621	J30W1	1	062.10009.0621	?	?	?	?	?	NO_KR	?
SKX_EXT_B_BGA1-IC,TBD	U2D1,U5D1	2	TBD	IC	?	?	?	?	?	?
SLG55021_SM-IC,G56246-001	EU2T1,EU7E1,EU8B1,EU9M1	4	G56246-001	IC	?	?	?	?	?	?
SMC-CON13-GP_CONN-GC2-SMC-CON13-GP,021.D0181.0113	J25W1	1	021.D0181.0113	?	?	?	?	?	AST2500	?
SMC-CONN60A-22-GP_CONN-G7-SMC-CONN60A-22-GP,020.C0082.0060	CONX8	1	020.C0082.0060	?	?	?	?	?	?	?
SN74LVC2G07DCKR-GP_DISCRET-G4-SN74LVC2G07DCKR-GP,73.02G07.02J	U8F3,U8G1	2	73.02G07.02J	?	?	?	?	?	?	?
SOCKET_P_MECH_A_LEFT-P0,PLASTIC,H37604-201	XLU1,XLU2	2	H37604-201	PLASTIC	?	?	?	?	?	?
SOCKET_P_MECH_A_RIGHT-P0,PLASTIC,H37604-101	XRU1,XRU2	2	H37604-101	PLASTIC	?	?	?	?	?	?
SPRINGVILLE_SM1-IC,G47144-004	EU9E1	1	G47144-004	IC	?	?	?	?	NI_I210&RJ45	?
ST220U10VDM-LGP_SMD-TCG-ST220U10VDM-LGP,77.22271.L03,220UF,IRP=2400MA,10V,ESR=25MOHM,TMAX=105C	C8E4	1	77.22271.L03	?	?	?	?	?	?	?
ST270U2D5VBM-GP_SMD-TCG2-ST270U2D5VBM-GP,077.C2771.0001	C1G7,C1G12,C1G15	3	077.C2771.0001	?	?	?	?	?	?	?
ST470U6D3VDM-7-GP_SMD-TCG4-ST470U6D3VDM-7-GP,077.C4771.0061,470UF,IRP=1.7A,6.3V,ESR=35MOHM,TMAX=105C	C8F8,C8F14	2	077.C4771.0061	?	?	?	?	?	?	?
STANDOFF_TH1-SO,H72821-001	RM8D1	1	H72821-001	SO	?	?	?	?	?	?
STFT363B238R224H453-GP_DISCRET-GC1-STFT363B238R224H453-GP,086.2AT24.04R6	RM1G1	1	086.2AT24.04R6	?	?	?	?	?	?	?
SW-SLIDE75-GP_DISCRET-G6-SW-SLIDE75-GP,62.40018.461	S9W1	1	62.40018.461	?	?	?	?	?	?	?
SWITCH_D37771002_SM-IC,D37771-002	S9A1,S9A2	2	D37771-002	IC	?	?	?	?	?	?
SWITCH_D90553001_SMLF-IC,D90553-001	S8E1	1	D90553-001	IC	?	?	?	?	?	?
TC7PZ14FU-GP_DISCRET-GA1-TC7PZ14FU-GP,073.7PZ14.0007	U2R1,U9A3,U9A4	3	073.7PZ14.0007	?	?	?	?	?	?	?
TCA9517DGKR-GP_DISCRET-G8-TCA9517DGKR-GP,071.09517.0009	U1B2,U1W2,U6W2,U32W1,U32W2	5	071.09517.0009	?	?	?	?	?	?	?
TCA9555PWR-GP_DISCRET-GC1-TCA9555PWR-GP,071.09555.000W	U6W1	1	071.09555.000W	?	?	?	?	?	?	?
TEST-PAD-12P-1-GP-U_DISCRET-GB1-TEST-PAD-12P-1-GP-U,ZZ.00PAD.MJ1	T1D1,T1D2,T1D3,T1D4,T1D5,T1D6,T1D7,T1D8,T1D9,T1D10,T1D11,T1D12,T1D13,T1D14,T1D15,T1D16,T1D17,T1D18,T1D19,T1D20,T1D21,T1D22,T1D23,T1D24	24	ZZ.00PAD.MJ1	?	?	?	?	?	?	?
TMP421_TSSOP-IC,G62962-001	U1E1,U9B4	2	G62962-001	IC	?	?	?	?	?	?
TPAD-DIFF-4P-GP_DISCRET-GB3-TPAD-DIFF-4P-GP,ZZ.00PAD.NW1	T1P1,T1P2,T1P3,T1P4,T1P5,T1P6,T1P7,T1P8,T1P9,T1P10,T1P11,T1P12,T1P14,T1P17,T1P19,T1P22,T1P23,T1P24	18	ZZ.00PAD.NW1	?	?	?	?	?	?	?
TPAD-SE-2P-GP_DISCRET-GA1-TPAD-SE-2P-GP,ZZ.00PAD.NU1	T1P25,T1P26,T1P27,T1P28,T1P29,T1P30,T1P31,T1P32,T1P33,T1P34,T1P35,T1P36	12	ZZ.00PAD.NU1	?	?	?	?	?	?	?
TPS2061_SM-IC,H66405-001	U1M3	1	H66405-001	IC	?	?	?	?	?	?
TPS3700_SM-IC,H69492-001	U1D2,U8D8,U9P1,U9P2	4	H69492-001	IC	?	?	?	?	?	?
TPS54821_LCC-IC,H63269-001	EU7E2	1	H63269-001	IC	?	?	?	?	?	?
TTL08_QFN15-74LVC08A,IC,D90404-001	U8E1	1	D90404-001	IC	?	?	?	?	?	?
TTL1G07_A_SOP-74LVC1G07,IC,C88419-001	U1L4,U1R1,U2P1,U8D2,U8D3,U8G2,U8G3,U9A1,U10W1,U25W9,U25W14,U25W15	12	C88419-001	IC	?	?	?	?	?	?
TTL1G07_A_SOP-74LVC1G07,IC,C88419-001	U9F3	1	C88419-001	IC	NOPOP	?	?	?	?	?
TTL1G08_SOTLF-NC7SZ08,IC,D10321-001	U1E2,U1M1,U7E2,U7E3,U14E2,U14E3,U25W17,U25W18	8	D10321-001	IC	?	?	?	?	?	?
TTL1G126_A_SOT-74HC1G126,IC,A79322-001	U1D1,U1R2,U6W4,U6W5,U6W6,U8D5,U8E3,U8E4,U25W19	9	A79322-001	IC	?	?	?	?	?	?
TTL1G32_A_SOT-74LVC1G32,IC,E60229-001	U2T2,U2T3	2	E60229-001	IC	?	?	?	?	NI_BIOS_ROM2	?
TTL1G86_SOTLF-74AHCT1G86,IC,D39848-001	U1L2	1	D39848-001	IC	?	?	?	?	?	?
TTL3126_QFNLF-74CBTLV3126,IC,D18317-001	U1L1,U1L5,U1L10,U25W12,U25W16	5	D18317-001	IC	?	?	?	?	?	?
U74AHCT1G125G-AL5-R-GP-U_TTL-G4-U74AHCT1G125G-AL5-R-GP-U,73.1G125.D0G	U25W7,U25W8	2	73.1G125.D0G	?	?	?	?	?	AST2500	?
VERT_BATT_3PIN_PIP-3PVERT,C68619-005	XBT8G1	1	C68619-005	3PVERT	?	?	?	?	?	?
W25Q128_SKT16-IC,H12709-001	U8F2	1	H12709-001	IC	?	?	?	?	?	?
W25Q256FVFIG-GP_MEMORY-G4-W25Q256FVFIG-GP,72.25256.H01	U3T1	1	72.25256.H01	?	?	?	?	?	NI_BIOS_ROM2	?
W25Q256_XSOI-IC,H25002-001	U7F1,UN8F2	2	H25002-001	IC	?	?	?	?	?	?
ZENER_SM-13V,IC,H69095-001	VR1D1	1	H69095-001	IC	?	?	?	?	?	?
TOTAL	 	4751	 	 	 	 	 	 	 	 
